FILE_TYPE = MACRO_DRAWING;
SET COLOR_WIRE YELLOW;
SET COLOR_PROP MONO;
SET COLOR_DOT WHITE;
SET COLOR_ARC YELLOW;
SET COLOR_BODY GREEN;
SET COLOR_NOTE MONO;
SET PROP_DISPLAY VALUE;
SET PAGE_NUMBER P247;
FORCEADD RES..2
R 2
(-7450 3350);
FORCEPROP 1 LAST PART_NUMBER G21796-072
J 2
(-7490 3225);
DISPLAY 0.617021 (-7490 3225);
PAINT BLUE (-7490 3225);
FORCEPROP 1 LAST MATERIAL CHIP
J 2
(-7490 3275);
DISPLAY 0.617021 (-7490 3275);
PAINT SKYBLUE (-7490 3275);
FORCEPROP 1 LASTPIN (-7450 3250) $PN 2
J 2
(-7455 3260);
DISPLAY 0.787234 (-7455 3260);
PAINT ORANGE (-7455 3260);
FORCEPROP 1 LAST WATTAGE 1/16W
J 2
(-7490 3325);
DISPLAY 0.617021 (-7490 3325);
PAINT SKYBLUE (-7490 3325);
FORCEPROP 1 LAST TOLERANCE 1%
J 2
(-7495 3375);
DISPLAY 0.617021 (-7495 3375);
PAINT SKYBLUE (-7495 3375);
FORCEPROP 1 LAST VALUE 4.75K
J 2
(-7495 3425);
DISPLAY 0.617021 (-7495 3425);
PAINT SKYBLUE (-7495 3425);
FORCEPROP 1 LAST LOCATION R6W10
J 2
(-7495 3475);
DISPLAY 0.617021 (-7495 3475);
PAINT AQUA (-7495 3475);
FORCEPROP 1 LASTPIN (-7450 3450) $PN 1
J 2
(-7455 3412);
DISPLAY 0.787234 (-7455 3412);
PAINT ORANGE (-7455 3412);
FORCEPROP 1 LAST PACK_TYPE 0402
J 2
(-7490 3175);
DISPLAY 0.617021 (-7490 3175);
PAINT SKYBLUE (-7490 3175);
FORCEPROP 2 LAST CDS_LIB mstr_discrete
J 0
(-7450 3350);
PAINT MONO (-7450 3350);
DISPLAY INVISIBLE (-7450 3350);
FORCEPROP 1 LAST PATH I1
J 2
(-7500 3525);
DISPLAY 0.978723 (-7500 3525);
PAINT WHITE (-7500 3525);
DISPLAY INVISIBLE (-7500 3525);
FORCEPROP 0 LAST ROOM CPU_FANS
J 0
(-7475 3575);
DISPLAY 1.021277 (-7475 3575);
PAINT ORANGE (-7475 3575);
DISPLAY INVISIBLE (-7475 3575);
FORCEPROP 0 LAST BOM_COST SM_THERM
J 0
(-7475 3675);
DISPLAY 1.021277 (-7475 3675);
PAINT ORANGE (-7475 3675);
DISPLAY INVISIBLE (-7475 3675);
FORCEPROP 2 LAST SEC_TYPE 0402
J 0
(-7500 3575);
DISPLAY 1.021277 (-7500 3575);
PAINT ORANGE (-7500 3575);
DISPLAY INVISIBLE (-7500 3575);
FORCEPROP 2 LAST SEC 1
J 0
(-7500 3575);
DISPLAY 0.680851 (-7500 3575);
PAINT MONO (-7500 3575);
DISPLAY INVISIBLE (-7500 3575);
FORCEADD RES..2
R 2
(-7550 1950);
FORCEPROP 1 LASTPIN (-7550 1850) $PN 2
J 2
(-7555 1860);
DISPLAY 0.787234 (-7555 1860);
PAINT ORANGE (-7555 1860);
FORCEPROP 1 LASTPIN (-7550 2050) $PN 1
J 2
(-7555 2012);
DISPLAY 0.787234 (-7555 2012);
PAINT ORANGE (-7555 2012);
FORCEPROP 1 LAST PACK_TYPE 0402
J 2
(-7590 1775);
DISPLAY 0.617021 (-7590 1775);
PAINT SKYBLUE (-7590 1775);
FORCEPROP 1 LAST PART_NUMBER G21796-072
J 2
(-7590 1825);
DISPLAY 0.617021 (-7590 1825);
PAINT BLUE (-7590 1825);
FORCEPROP 1 LAST TOLERANCE 1%
J 2
(-7595 1975);
DISPLAY 0.617021 (-7595 1975);
PAINT SKYBLUE (-7595 1975);
FORCEPROP 1 LAST WATTAGE 1/16W
J 2
(-7590 1925);
DISPLAY 0.617021 (-7590 1925);
PAINT SKYBLUE (-7590 1925);
FORCEPROP 1 LAST MATERIAL CHIP
J 2
(-7590 1875);
DISPLAY 0.617021 (-7590 1875);
PAINT SKYBLUE (-7590 1875);
FORCEPROP 1 LAST LOCATION R6W24
J 2
(-7595 2075);
DISPLAY 0.617021 (-7595 2075);
PAINT AQUA (-7595 2075);
FORCEPROP 1 LAST VALUE 4.75K
J 2
(-7595 2025);
DISPLAY 0.617021 (-7595 2025);
PAINT SKYBLUE (-7595 2025);
FORCEPROP 2 LAST SEC_TYPE 0402
J 0
(-7600 2175);
DISPLAY 1.021277 (-7600 2175);
PAINT ORANGE (-7600 2175);
DISPLAY INVISIBLE (-7600 2175);
FORCEPROP 0 LAST SEC 1
J 0
(-7575 2125);
DISPLAY 0.680851 (-7575 2125);
PAINT MONO (-7575 2125);
DISPLAY INVISIBLE (-7575 2125);
FORCEPROP 0 LAST ROOM CPU_FANS
J 0
(-7575 2175);
DISPLAY 1.021277 (-7575 2175);
PAINT ORANGE (-7575 2175);
DISPLAY INVISIBLE (-7575 2175);
FORCEPROP 0 LAST BOM_COST SM_THERM
J 0
(-7575 2275);
DISPLAY 1.021277 (-7575 2275);
PAINT ORANGE (-7575 2275);
DISPLAY INVISIBLE (-7575 2275);
FORCEPROP 1 LAST PATH I100
J 2
(-7600 2125);
DISPLAY 0.978723 (-7600 2125);
PAINT WHITE (-7600 2125);
DISPLAY INVISIBLE (-7600 2125);
FORCEPROP 2 LAST CDS_LIB mstr_discrete
J 0
(-7550 1950);
PAINT MONO (-7550 1950);
DISPLAY INVISIBLE (-7550 1950);
FORCEADD RES..2
R 2
(-7200 1950);
FORCEPROP 1 LASTPIN (-7200 1850) $PN 2
J 2
(-7205 1860);
DISPLAY 0.787234 (-7205 1860);
PAINT ORANGE (-7205 1860);
FORCEPROP 1 LASTPIN (-7200 2050) $PN 1
J 2
(-7205 2012);
DISPLAY 0.787234 (-7205 2012);
PAINT ORANGE (-7205 2012);
FORCEPROP 1 LAST PACK_TYPE 0402
J 2
(-7240 1775);
DISPLAY 0.617021 (-7240 1775);
PAINT SKYBLUE (-7240 1775);
FORCEPROP 1 LAST WATTAGE 1/16W
J 2
(-7240 1925);
DISPLAY 0.617021 (-7240 1925);
PAINT SKYBLUE (-7240 1925);
FORCEPROP 1 LAST MATERIAL CHIP
J 2
(-7240 1875);
DISPLAY 0.617021 (-7240 1875);
PAINT SKYBLUE (-7240 1875);
FORCEPROP 1 LAST PART_NUMBER G21796-072
J 2
(-7240 1825);
DISPLAY 0.617021 (-7240 1825);
PAINT BLUE (-7240 1825);
FORCEPROP 1 LAST TOLERANCE 1%
J 2
(-7245 1975);
DISPLAY 0.617021 (-7245 1975);
PAINT SKYBLUE (-7245 1975);
FORCEPROP 1 LAST VALUE 4.75K
J 2
(-7245 2025);
DISPLAY 0.617021 (-7245 2025);
PAINT SKYBLUE (-7245 2025);
FORCEPROP 1 LAST LOCATION R6W25
J 2
(-7245 2075);
DISPLAY 0.617021 (-7245 2075);
PAINT AQUA (-7245 2075);
FORCEPROP 2 LAST SEC_TYPE 0402
J 0
(-7250 2175);
DISPLAY 1.021277 (-7250 2175);
PAINT ORANGE (-7250 2175);
DISPLAY INVISIBLE (-7250 2175);
FORCEPROP 0 LAST SEC 1
J 0
(-7225 2125);
DISPLAY 0.680851 (-7225 2125);
PAINT MONO (-7225 2125);
DISPLAY INVISIBLE (-7225 2125);
FORCEPROP 2 LAST CDS_LIB mstr_discrete
J 0
(-7200 1950);
PAINT MONO (-7200 1950);
DISPLAY INVISIBLE (-7200 1950);
FORCEPROP 1 LAST PATH I101
J 2
(-7250 2125);
DISPLAY 0.978723 (-7250 2125);
PAINT WHITE (-7250 2125);
DISPLAY INVISIBLE (-7250 2125);
FORCEPROP 0 LAST ROOM CPU_FANS
J 0
(-7225 2175);
DISPLAY 1.021277 (-7225 2175);
PAINT ORANGE (-7225 2175);
DISPLAY INVISIBLE (-7225 2175);
FORCEPROP 0 LAST BOM_COST SM_THERM
J 0
(-7225 2275);
DISPLAY 1.021277 (-7225 2275);
PAINT ORANGE (-7225 2275);
DISPLAY INVISIBLE (-7225 2275);
FORCEADD P3V3_STBY..1
(-7550 2250);
FORCEPROP 3 LASTPIN (-7550 2200) SIG_NAME P3V3_STBY\g
J 0
(-7540 2210);
DISPLAY 0.659574 (-7540 2210);
PAINT MONO (-7540 2210);
DISPLAY INVISIBLE (-7540 2210);
FORCEPROP 1 LAST HDL_POWER P3V3_STBY
J 0
(-7850 2125);
DISPLAY 0.872340 (-7850 2125);
PAINT ORANGE (-7850 2125);
DISPLAY INVISIBLE (-7850 2125);
FORCEPROP 1 LAST BODY_TYPE PLUMBING
J 0
(-7595 2207);
DISPLAY 0.340426 (-7595 2207);
PAINT GREEN (-7595 2207);
DISPLAY INVISIBLE (-7595 2207);
FORCEPROP 1 LAST SIZE 1B
J 0
(-7505 2272);
DISPLAY 0.340426 (-7505 2272);
PAINT GREEN (-7505 2272);
DISPLAY INVISIBLE (-7505 2272);
FORCEPROP 1 LAST VOLTAGE 3.3V
J 0
(-7595 2207);
DISPLAY 0.340426 (-7595 2207);
PAINT GREEN (-7595 2207);
DISPLAY INVISIBLE (-7595 2207);
FORCEPROP 1 LAST PATH I102
J 0
(-7505 2252);
DISPLAY 0.340426 (-7505 2252);
PAINT GREEN (-7505 2252);
DISPLAY INVISIBLE (-7505 2252);
FORCEPROP 2 LAST CDS_LIB mstr_symbols
J 0
(-7550 2250);
PAINT MONO (-7550 2250);
DISPLAY INVISIBLE (-7550 2250);
FORCEADD GND..1
(-7250 1050);
FORCEPROP 3 LASTPIN (-7250 1100) SIG_NAME GND\g
J 0
(-7240 1110);
DISPLAY 0.659574 (-7240 1110);
PAINT MONO (-7240 1110);
DISPLAY INVISIBLE (-7240 1110);
FORCEPROP 1 LAST HDL_POWER GND
J 0
(-7250 1200);
DISPLAY 0.872340 (-7250 1200);
PAINT GREEN (-7250 1200);
DISPLAY INVISIBLE (-7250 1200);
FORCEPROP 1 LAST BODY_TYPE PLUMBING
J 0
(-7295 1007);
DISPLAY 0.340426 (-7295 1007);
PAINT GREEN (-7295 1007);
DISPLAY INVISIBLE (-7295 1007);
FORCEPROP 1 LAST VOLTAGE 0
J 0
(-7250 1050);
PAINT SKYBLUE (-7250 1050);
DISPLAY INVISIBLE (-7250 1050);
FORCEPROP 2 LAST CDS_LIB mstr_symbols
J 0
(-7250 1050);
PAINT MONO (-7250 1050);
DISPLAY INVISIBLE (-7250 1050);
FORCEPROP 1 LAST SIZE 1B
J 0
(-7175 1000);
DISPLAY 0.872340 (-7175 1000);
PAINT GREEN (-7175 1000);
DISPLAY INVISIBLE (-7175 1000);
FORCEPROP 2 LAST BOM_COST NT_BASE_VRD
J 0
(-7550 1125);
DISPLAY 0.617021 (-7550 1125);
PAINT ORANGE (-7550 1125);
DISPLAY INVISIBLE (-7550 1125);
FORCEPROP 2 LAST ROOM P2V5_LAN_AUX_VR
J 0
(-7550 1125);
DISPLAY 0.617021 (-7550 1125);
PAINT ORANGE (-7550 1125);
DISPLAY INVISIBLE (-7550 1125);
FORCEPROP 1 LAST PATH I104
J 0
(-7175 1050);
DISPLAY 0.872340 (-7175 1050);
PAINT AQUA (-7175 1050);
DISPLAY INVISIBLE (-7175 1050);
FORCEADD CAP_A..1
(-7250 1250);
FORCEPROP 1 LAST PACK_TYPE 0402V
J 0
(-7200 1050);
DISPLAY 0.617021 (-7200 1050);
PAINT SKYBLUE (-7200 1050);
FORCEPROP 1 LAST MATERIAL X7R
J 0
(-7200 1150);
DISPLAY 0.617021 (-7200 1150);
PAINT SKYBLUE (-7200 1150);
FORCEPROP 1 LAST TOLERANCE 10%
J 0
(-7200 1200);
DISPLAY 0.617021 (-7200 1200);
PAINT SKYBLUE (-7200 1200);
FORCEPROP 1 LAST VOLTAGE 16V
J 0
(-7200 1250);
DISPLAY 0.617021 (-7200 1250);
PAINT SKYBLUE (-7200 1250);
FORCEPROP 1 LAST VALUE 0.1UF
J 0
(-7200 1300);
DISPLAY 0.617021 (-7200 1300);
PAINT SKYBLUE (-7200 1300);
FORCEPROP 1 LAST LOCATION C6W4
J 0
(-7200 1350);
DISPLAY 0.617021 (-7200 1350);
PAINT AQUA (-7200 1350);
FORCEPROP 1 LASTPIN (-7250 1350) $PN 1
J 0
(-7240 1330);
DISPLAY 0.617021 (-7240 1330);
PAINT ORANGE (-7240 1330);
FORCEPROP 1 LASTPIN (-7250 1150) $PN 2
J 0
(-7240 1130);
DISPLAY 0.617021 (-7240 1130);
PAINT ORANGE (-7240 1130);
FORCEPROP 1 LAST PART_NUMBER A36096-030
J 0
(-7200 1100);
DISPLAY 0.617021 (-7200 1100);
PAINT BLUE (-7200 1100);
FORCEPROP 2 LAST CDS_LOCATION C6W4
J 0
(-7200 1350);
DISPLAY 0.617021 (-7200 1350);
PAINT AQUA (-7200 1350);
DISPLAY INVISIBLE (-7200 1350);
FORCEPROP 1 LAST PATH I105
J 0
(-7200 1400);
DISPLAY 0.978723 (-7200 1400);
PAINT WHITE (-7200 1400);
DISPLAY INVISIBLE (-7200 1400);
FORCEPROP 0 LAST CDS_SEC 1
J 0
(-7200 1400);
PAINT MONO (-7200 1400);
DISPLAY INVISIBLE (-7200 1400);
FORCEPROP 0 LAST ROOM SMB_PE_HP_CPU1
J 0
(-7200 1450);
DISPLAY 1.021277 (-7200 1450);
PAINT ORANGE (-7200 1450);
DISPLAY INVISIBLE (-7200 1450);
FORCEPROP 2 LAST SEC_TYPE 0402V
J 0
(-7200 1450);
DISPLAY 1.021277 (-7200 1450);
PAINT ORANGE (-7200 1450);
DISPLAY INVISIBLE (-7200 1450);
FORCEPROP 2 LAST SEC 1
J 0
(-7200 1450);
DISPLAY 0.680851 (-7200 1450);
PAINT MONO (-7200 1450);
DISPLAY INVISIBLE (-7200 1450);
FORCEPROP 2 LAST CDS_LIB dev_discrete
J 0
(-7250 1250);
PAINT ORANGE (-7250 1250);
DISPLAY INVISIBLE (-7250 1250);
FORCEADD CAP_A..1
R 2
(-5500 1250);
FORCEPROP 1 LAST VALUE 0.1UF
J 2
(-5550 1300);
DISPLAY 0.617021 (-5550 1300);
PAINT SKYBLUE (-5550 1300);
FORCEPROP 1 LAST TOLERANCE 10%
J 2
(-5550 1200);
DISPLAY 0.617021 (-5550 1200);
PAINT SKYBLUE (-5550 1200);
FORCEPROP 1 LAST PART_NUMBER A36096-030
J 2
(-5550 1100);
DISPLAY 0.617021 (-5550 1100);
PAINT BLUE (-5550 1100);
FORCEPROP 1 LAST LOCATION C6W2
J 2
(-5550 1350);
DISPLAY 0.617021 (-5550 1350);
PAINT AQUA (-5550 1350);
FORCEPROP 1 LAST VOLTAGE 16V
J 2
(-5550 1250);
DISPLAY 0.617021 (-5550 1250);
PAINT SKYBLUE (-5550 1250);
FORCEPROP 1 LASTPIN (-5500 1350) $PN 1
J 2
(-5510 1330);
DISPLAY 0.617021 (-5510 1330);
PAINT ORANGE (-5510 1330);
FORCEPROP 1 LAST MATERIAL X7R
J 2
(-5550 1150);
DISPLAY 0.617021 (-5550 1150);
PAINT SKYBLUE (-5550 1150);
FORCEPROP 1 LASTPIN (-5500 1150) $PN 2
J 2
(-5510 1130);
DISPLAY 0.617021 (-5510 1130);
PAINT ORANGE (-5510 1130);
FORCEPROP 1 LAST PACK_TYPE 0402V
J 2
(-5550 1050);
DISPLAY 0.617021 (-5550 1050);
PAINT SKYBLUE (-5550 1050);
FORCEPROP 2 LAST CDS_LOCATION C6W2
J 2
(-5550 1350);
DISPLAY 0.617021 (-5550 1350);
PAINT AQUA (-5550 1350);
DISPLAY INVISIBLE (-5550 1350);
FORCEPROP 2 LAST SEC_TYPE 0402V
J 0
(-5550 1450);
DISPLAY 1.021277 (-5550 1450);
PAINT ORANGE (-5550 1450);
DISPLAY INVISIBLE (-5550 1450);
FORCEPROP 2 LAST SEC 1
J 0
(-5550 1450);
DISPLAY 0.680851 (-5550 1450);
PAINT MONO (-5550 1450);
DISPLAY INVISIBLE (-5550 1450);
FORCEPROP 2 LAST CDS_LIB dev_discrete
J 0
(-5500 1250);
PAINT ORANGE (-5500 1250);
DISPLAY INVISIBLE (-5500 1250);
FORCEPROP 0 LAST ROOM SMB_PE_HP_CPU1
J 0
(-5550 1450);
DISPLAY 1.021277 (-5550 1450);
PAINT ORANGE (-5550 1450);
DISPLAY INVISIBLE (-5550 1450);
FORCEPROP 0 LAST CDS_SEC 1
J 0
(-5550 1400);
PAINT MONO (-5550 1400);
DISPLAY INVISIBLE (-5550 1400);
FORCEPROP 1 LAST PATH I107
J 2
(-5550 1400);
DISPLAY 0.978723 (-5550 1400);
PAINT WHITE (-5550 1400);
DISPLAY INVISIBLE (-5550 1400);
FORCEADD GND..1
(-5500 1050);
FORCEPROP 3 LASTPIN (-5500 1100) SIG_NAME GND\g
J 0
(-5490 1110);
DISPLAY 0.659574 (-5490 1110);
PAINT MONO (-5490 1110);
DISPLAY INVISIBLE (-5490 1110);
FORCEPROP 1 LAST HDL_POWER GND
J 0
(-5500 1200);
DISPLAY 0.872340 (-5500 1200);
PAINT GREEN (-5500 1200);
DISPLAY INVISIBLE (-5500 1200);
FORCEPROP 1 LAST BODY_TYPE PLUMBING
J 0
(-5545 1007);
DISPLAY 0.340426 (-5545 1007);
PAINT GREEN (-5545 1007);
DISPLAY INVISIBLE (-5545 1007);
FORCEPROP 1 LAST PATH I108
J 0
(-5425 1050);
DISPLAY 0.872340 (-5425 1050);
PAINT AQUA (-5425 1050);
DISPLAY INVISIBLE (-5425 1050);
FORCEPROP 2 LAST ROOM P2V5_LAN_AUX_VR
J 0
(-5800 1125);
DISPLAY 0.617021 (-5800 1125);
PAINT ORANGE (-5800 1125);
DISPLAY INVISIBLE (-5800 1125);
FORCEPROP 2 LAST BOM_COST NT_BASE_VRD
J 0
(-5800 1125);
DISPLAY 0.617021 (-5800 1125);
PAINT ORANGE (-5800 1125);
DISPLAY INVISIBLE (-5800 1125);
FORCEPROP 1 LAST SIZE 1B
J 0
(-5425 1000);
DISPLAY 0.872340 (-5425 1000);
PAINT GREEN (-5425 1000);
DISPLAY INVISIBLE (-5425 1000);
FORCEPROP 2 LAST CDS_LIB mstr_symbols
J 0
(-5500 1050);
PAINT MONO (-5500 1050);
DISPLAY INVISIBLE (-5500 1050);
FORCEPROP 1 LAST VOLTAGE 0
J 0
(-5500 1050);
PAINT SKYBLUE (-5500 1050);
DISPLAY INVISIBLE (-5500 1050);
FORCEADD P3V3_STBY..1
(-5950 1500);
FORCEPROP 3 LASTPIN (-5950 1450) SIG_NAME P3V3_STBY\g
J 0
(-5940 1460);
DISPLAY 0.659574 (-5940 1460);
PAINT MONO (-5940 1460);
DISPLAY INVISIBLE (-5940 1460);
FORCEPROP 1 LAST HDL_POWER P3V3_STBY
J 0
(-6250 1375);
DISPLAY 0.872340 (-6250 1375);
PAINT ORANGE (-6250 1375);
DISPLAY INVISIBLE (-6250 1375);
FORCEPROP 1 LAST BODY_TYPE PLUMBING
J 0
(-5995 1457);
DISPLAY 0.340426 (-5995 1457);
PAINT GREEN (-5995 1457);
DISPLAY INVISIBLE (-5995 1457);
FORCEPROP 1 LAST SIZE 1B
J 0
(-5905 1522);
DISPLAY 0.340426 (-5905 1522);
PAINT GREEN (-5905 1522);
DISPLAY INVISIBLE (-5905 1522);
FORCEPROP 2 LAST CDS_LIB mstr_symbols
J 0
(-5950 1500);
PAINT ORANGE (-5950 1500);
DISPLAY INVISIBLE (-5950 1500);
FORCEPROP 1 LAST VOLTAGE 3.3V
J 0
(-5995 1457);
DISPLAY 0.340426 (-5995 1457);
PAINT SKYBLUE (-5995 1457);
DISPLAY INVISIBLE (-5995 1457);
FORCEPROP 1 LAST PATH I109
J 0
(-5905 1502);
DISPLAY 0.340426 (-5905 1502);
PAINT GREEN (-5905 1502);
DISPLAY INVISIBLE (-5905 1502);
FORCEADD P3V3_STBY..1
(-6900 1500);
FORCEPROP 3 LASTPIN (-6900 1450) SIG_NAME P3V3_STBY\g
J 0
(-6890 1460);
DISPLAY 0.659574 (-6890 1460);
PAINT MONO (-6890 1460);
DISPLAY INVISIBLE (-6890 1460);
FORCEPROP 1 LAST HDL_POWER P3V3_STBY
J 0
(-7200 1375);
DISPLAY 0.872340 (-7200 1375);
PAINT ORANGE (-7200 1375);
DISPLAY INVISIBLE (-7200 1375);
FORCEPROP 1 LAST BODY_TYPE PLUMBING
J 0
(-6945 1457);
DISPLAY 0.340426 (-6945 1457);
PAINT GREEN (-6945 1457);
DISPLAY INVISIBLE (-6945 1457);
FORCEPROP 2 LAST CDS_LIB mstr_symbols
J 0
(-6900 1500);
PAINT MONO (-6900 1500);
DISPLAY INVISIBLE (-6900 1500);
FORCEPROP 1 LAST PATH I111
J 0
(-6855 1502);
DISPLAY 0.340426 (-6855 1502);
PAINT GREEN (-6855 1502);
DISPLAY INVISIBLE (-6855 1502);
FORCEPROP 1 LAST VOLTAGE 3.3V
J 0
(-6945 1457);
DISPLAY 0.340426 (-6945 1457);
PAINT SKYBLUE (-6945 1457);
DISPLAY INVISIBLE (-6945 1457);
FORCEPROP 1 LAST SIZE 1B
J 0
(-6855 1522);
DISPLAY 0.340426 (-6855 1522);
PAINT GREEN (-6855 1522);
DISPLAY INVISIBLE (-6855 1522);
FORCEADD RES..2
R 2
(-6850 1950);
FORCEPROP 1 LASTPIN (-6850 1850) $PN 2
J 2
(-6855 1860);
DISPLAY 0.787234 (-6855 1860);
PAINT ORANGE (-6855 1860);
FORCEPROP 1 LASTPIN (-6850 2050) $PN 1
J 2
(-6855 2012);
DISPLAY 0.787234 (-6855 2012);
PAINT ORANGE (-6855 2012);
FORCEPROP 1 LAST PACK_TYPE 0402
J 2
(-6890 1775);
DISPLAY 0.617021 (-6890 1775);
PAINT SKYBLUE (-6890 1775);
FORCEPROP 1 LAST MATERIAL CHIP
J 2
(-6890 1875);
DISPLAY 0.617021 (-6890 1875);
PAINT SKYBLUE (-6890 1875);
FORCEPROP 1 LAST PART_NUMBER G21796-072
J 2
(-6890 1825);
DISPLAY 0.617021 (-6890 1825);
PAINT BLUE (-6890 1825);
FORCEPROP 1 LAST TOLERANCE 1%
J 2
(-6895 1975);
DISPLAY 0.617021 (-6895 1975);
PAINT SKYBLUE (-6895 1975);
FORCEPROP 1 LAST WATTAGE 1/16W
J 2
(-6890 1925);
DISPLAY 0.617021 (-6890 1925);
PAINT SKYBLUE (-6890 1925);
FORCEPROP 1 LAST VALUE 4.75K
J 2
(-6895 2025);
DISPLAY 0.617021 (-6895 2025);
PAINT SKYBLUE (-6895 2025);
FORCEPROP 1 LAST LOCATION R6W28
J 2
(-6895 2075);
DISPLAY 0.617021 (-6895 2075);
PAINT AQUA (-6895 2075);
FORCEPROP 2 LAST SEC_TYPE 0402
J 0
(-6900 2175);
DISPLAY 1.021277 (-6900 2175);
PAINT ORANGE (-6900 2175);
DISPLAY INVISIBLE (-6900 2175);
FORCEPROP 0 LAST SEC 1
J 0
(-6875 2125);
DISPLAY 0.680851 (-6875 2125);
PAINT MONO (-6875 2125);
DISPLAY INVISIBLE (-6875 2125);
FORCEPROP 0 LAST BOM_COST SM_THERM
J 0
(-6875 2275);
DISPLAY 1.021277 (-6875 2275);
PAINT ORANGE (-6875 2275);
DISPLAY INVISIBLE (-6875 2275);
FORCEPROP 0 LAST ROOM CPU_FANS
J 0
(-6875 2175);
DISPLAY 1.021277 (-6875 2175);
PAINT ORANGE (-6875 2175);
DISPLAY INVISIBLE (-6875 2175);
FORCEPROP 1 LAST PATH I112
J 2
(-6900 2125);
DISPLAY 0.978723 (-6900 2125);
PAINT WHITE (-6900 2125);
DISPLAY INVISIBLE (-6900 2125);
FORCEPROP 2 LAST CDS_LIB mstr_discrete
J 0
(-6850 1950);
PAINT MONO (-6850 1950);
DISPLAY INVISIBLE (-6850 1950);
FORCEADD TCA9517DGKR-GP..1
(-6375 925);
FORCEPROP 2 LASTPIN (-6700 1000) $PN 1
J 2
(-6710 1010);
DISPLAY 0.808511 (-6710 1010);
PAINT ORANGE (-6710 1010);
FORCEPROP 1 LAST LOCATION U6W2
J 0
(-6545 1110);
DISPLAY 0.617021 (-6545 1110);
PAINT GREEN (-6545 1110);
FORCEPROP 2 LASTPIN (-6050 950) $PN 7
J 0
(-6040 960);
DISPLAY 0.808511 (-6040 960);
PAINT ORANGE (-6040 960);
FORCEPROP 2 LASTPIN (-6050 1000) $PN 8
J 0
(-6040 1010);
DISPLAY 0.808511 (-6040 1010);
PAINT ORANGE (-6040 1010);
FORCEPROP 2 LASTPIN (-6050 900) $PN 6
J 0
(-6040 910);
DISPLAY 0.808511 (-6040 910);
PAINT ORANGE (-6040 910);
FORCEPROP 2 LASTPIN (-6700 950) $PN 2
J 2
(-6710 960);
DISPLAY 0.808511 (-6710 960);
PAINT ORANGE (-6710 960);
FORCEPROP 2 LASTPIN (-6700 900) $PN 3
J 2
(-6710 910);
DISPLAY 0.808511 (-6710 910);
PAINT ORANGE (-6710 910);
FORCEPROP 1 LAST VALUE TCA9517DGKR-GP
J 0
(-6545 715);
DISPLAY 0.617021 (-6545 715);
PAINT GREEN (-6545 715);
FORCEPROP 2 LASTPIN (-6050 850) $PN 5
J 0
(-6040 860);
DISPLAY 0.808511 (-6040 860);
PAINT ORANGE (-6040 860);
FORCEPROP 2 LASTPIN (-6700 850) $PN 4
J 2
(-6710 860);
DISPLAY 0.808511 (-6710 860);
PAINT ORANGE (-6710 860);
FORCEPROP 1 LAST PACK_TYPE DISCRET-G8
J 0
(-6375 925);
DISPLAY 0.617021 (-6375 925);
PAINT GREEN (-6375 925);
DISPLAY INVISIBLE (-6375 925);
FORCEPROP 2 LAST SEC 1
J 0
(-6525 1150);
DISPLAY 0.680851 (-6525 1150);
PAINT MONO (-6525 1150);
DISPLAY INVISIBLE (-6525 1150);
FORCEPROP 2 LAST SEC_TYPE DISCRET-G8
J 0
(-6525 1150);
DISPLAY 1.021277 (-6525 1150);
PAINT ORANGE (-6525 1150);
DISPLAY INVISIBLE (-6525 1150);
FORCEPROP 1 LAST PART_NUMBER 071.09517.0009
J 0
(-6375 925);
DISPLAY 0.617021 (-6375 925);
PAINT GREEN (-6375 925);
DISPLAY INVISIBLE (-6375 925);
FORCEPROP 2 LAST CDS_LIB w_hdl
J 0
(-6375 925);
PAINT MONO (-6375 925);
DISPLAY INVISIBLE (-6375 925);
FORCEPROP 1 LAST PATH I118
J 0
(-6375 925);
DISPLAY 0.617021 (-6375 925);
PAINT GREEN (-6375 925);
DISPLAY INVISIBLE (-6375 925);
FORCEPROP 1 LAST CDS_LMAN_SYM_OUTLINE -175,175,175,-175
J 0
(-6375 925);
DISPLAY 0.468085 (-6375 925);
PAINT GREEN (-6375 925);
DISPLAY INVISIBLE (-6375 925);
FORCEADD GND..1
(-6750 750);
FORCEPROP 3 LASTPIN (-6750 800) SIG_NAME GND\g
J 0
(-6740 810);
DISPLAY 0.659574 (-6740 810);
PAINT MONO (-6740 810);
DISPLAY INVISIBLE (-6740 810);
FORCEPROP 1 LAST HDL_POWER GND
J 0
(-6750 900);
DISPLAY 0.872340 (-6750 900);
PAINT GREEN (-6750 900);
DISPLAY INVISIBLE (-6750 900);
FORCEPROP 1 LAST BODY_TYPE PLUMBING
J 0
(-6795 707);
DISPLAY 0.340426 (-6795 707);
PAINT GREEN (-6795 707);
DISPLAY INVISIBLE (-6795 707);
FORCEPROP 1 LAST VOLTAGE 0
J 0
(-6750 750);
PAINT SKYBLUE (-6750 750);
DISPLAY INVISIBLE (-6750 750);
FORCEPROP 2 LAST CDS_LIB mstr_symbols
J 0
(-6750 750);
PAINT MONO (-6750 750);
DISPLAY INVISIBLE (-6750 750);
FORCEPROP 1 LAST SIZE 1B
J 0
(-6675 700);
DISPLAY 0.872340 (-6675 700);
PAINT GREEN (-6675 700);
DISPLAY INVISIBLE (-6675 700);
FORCEPROP 2 LAST BOM_COST NT_BASE_VRD
J 0
(-7050 825);
DISPLAY 0.617021 (-7050 825);
PAINT ORANGE (-7050 825);
DISPLAY INVISIBLE (-7050 825);
FORCEPROP 2 LAST ROOM P2V5_LAN_AUX_VR
J 0
(-7050 825);
DISPLAY 0.617021 (-7050 825);
PAINT ORANGE (-7050 825);
DISPLAY INVISIBLE (-7050 825);
FORCEPROP 1 LAST PATH I119
J 0
(-6675 750);
DISPLAY 0.872340 (-6675 750);
PAINT AQUA (-6675 750);
DISPLAY INVISIBLE (-6675 750);
FORCEADD P3V3_STBY..1
(-7450 3700);
FORCEPROP 3 LASTPIN (-7450 3650) SIG_NAME P3V3_STBY\g
J 0
(-7440 3660);
DISPLAY 0.659574 (-7440 3660);
PAINT MONO (-7440 3660);
DISPLAY INVISIBLE (-7440 3660);
FORCEPROP 1 LAST HDL_POWER P3V3_STBY
J 0
(-7750 3575);
DISPLAY 0.872340 (-7750 3575);
PAINT ORANGE (-7750 3575);
DISPLAY INVISIBLE (-7750 3575);
FORCEPROP 1 LAST BODY_TYPE PLUMBING
J 0
(-7495 3657);
DISPLAY 0.340426 (-7495 3657);
PAINT GREEN (-7495 3657);
DISPLAY INVISIBLE (-7495 3657);
FORCEPROP 2 LAST CDS_LIB mstr_symbols
J 0
(-7450 3700);
PAINT MONO (-7450 3700);
DISPLAY INVISIBLE (-7450 3700);
FORCEPROP 1 LAST PATH I12
J 0
(-7405 3702);
DISPLAY 0.340426 (-7405 3702);
PAINT GREEN (-7405 3702);
DISPLAY INVISIBLE (-7405 3702);
FORCEPROP 1 LAST SIZE 1B
J 0
(-7405 3722);
DISPLAY 0.340426 (-7405 3722);
PAINT GREEN (-7405 3722);
DISPLAY INVISIBLE (-7405 3722);
FORCEPROP 1 LAST VOLTAGE 3.3V
J 0
(-7495 3657);
DISPLAY 0.340426 (-7495 3657);
PAINT GREEN (-7495 3657);
DISPLAY INVISIBLE (-7495 3657);
FORCEADD TCA9555PWR-GP..1
(-3950 3675);
FORCEPROP 2 LASTPIN (-3600 3600) $PN 17
J 0
(-3590 3610);
DISPLAY 0.808511 (-3590 3610);
PAINT ORANGE (-3590 3610);
FORCEPROP 2 LASTPIN (-3600 3450) $PN 20
J 0
(-3590 3460);
DISPLAY 0.808511 (-3590 3460);
PAINT ORANGE (-3590 3460);
FORCEPROP 1 LAST VALUE TCA9555PWR-GP
J 0
(-4160 3165);
DISPLAY 0.617021 (-4160 3165);
PAINT GREEN (-4160 3165);
FORCEPROP 2 LASTPIN (-3600 3300) $PN 12
J 0
(-3590 3310);
DISPLAY 0.808511 (-3590 3310);
PAINT ORANGE (-3590 3310);
FORCEPROP 2 LASTPIN (-4300 3450) $PN 8
J 2
(-4310 3460);
DISPLAY 0.808511 (-4310 3460);
PAINT ORANGE (-4310 3460);
FORCEPROP 2 LASTPIN (-4300 3650) $PN 4
J 2
(-4310 3660);
DISPLAY 0.808511 (-4310 3660);
PAINT ORANGE (-4310 3660);
FORCEPROP 2 LASTPIN (-4300 3400) $PN 9
J 2
(-4310 3410);
DISPLAY 0.808511 (-4310 3410);
PAINT ORANGE (-4310 3410);
FORCEPROP 2 LASTPIN (-4300 3500) $PN 7
J 2
(-4310 3510);
DISPLAY 0.808511 (-4310 3510);
PAINT ORANGE (-4310 3510);
FORCEPROP 2 LASTPIN (-4300 3900) $PN 21
J 2
(-4310 3910);
DISPLAY 0.808511 (-4310 3910);
PAINT ORANGE (-4310 3910);
FORCEPROP 2 LASTPIN (-3600 3500) $PN 19
J 0
(-3590 3510);
DISPLAY 0.808511 (-3590 3510);
PAINT ORANGE (-3590 3510);
FORCEPROP 2 LASTPIN (-3600 3650) $PN 16
J 0
(-3590 3660);
DISPLAY 0.808511 (-3590 3660);
PAINT ORANGE (-3590 3660);
FORCEPROP 2 LASTPIN (-3600 3900) $PN 22
J 0
(-3590 3910);
DISPLAY 0.808511 (-3590 3910);
PAINT ORANGE (-3590 3910);
FORCEPROP 2 LASTPIN (-4300 4050) $PN 24
J 2
(-4310 4060);
DISPLAY 0.808511 (-4310 4060);
PAINT ORANGE (-4310 4060);
FORCEPROP 2 LASTPIN (-4300 3300) $PN 11
J 2
(-4310 3310);
DISPLAY 0.808511 (-4310 3310);
PAINT ORANGE (-4310 3310);
FORCEPROP 2 LASTPIN (-4300 3350) $PN 10
J 2
(-4310 3360);
DISPLAY 0.808511 (-4310 3360);
PAINT ORANGE (-4310 3360);
FORCEPROP 2 LASTPIN (-4300 3550) $PN 6
J 2
(-4310 3560);
DISPLAY 0.808511 (-4310 3560);
PAINT ORANGE (-4310 3560);
FORCEPROP 2 LASTPIN (-4300 3800) $PN 3
J 2
(-4310 3810);
DISPLAY 0.808511 (-4310 3810);
PAINT ORANGE (-4310 3810);
FORCEPROP 2 LASTPIN (-4300 3850) $PN 2
J 2
(-4310 3860);
DISPLAY 0.808511 (-4310 3860);
PAINT ORANGE (-4310 3860);
FORCEPROP 2 LASTPIN (-3600 3700) $PN 15
J 0
(-3590 3710);
DISPLAY 0.808511 (-3590 3710);
PAINT ORANGE (-3590 3710);
FORCEPROP 1 LAST LOCATION U6W1
J 0
(-4160 4165);
DISPLAY 0.617021 (-4160 4165);
PAINT GREEN (-4160 4165);
FORCEPROP 2 LASTPIN (-3600 3550) $PN 18
J 0
(-3590 3560);
DISPLAY 0.808511 (-3590 3560);
PAINT ORANGE (-3590 3560);
FORCEPROP 2 LASTPIN (-3600 4050) $PN 1
J 0
(-3590 4060);
DISPLAY 0.808511 (-3590 4060);
PAINT ORANGE (-3590 4060);
FORCEPROP 2 LASTPIN (-3600 3950) $PN 23
J 0
(-3590 3960);
DISPLAY 0.808511 (-3590 3960);
PAINT ORANGE (-3590 3960);
FORCEPROP 2 LASTPIN (-3600 3800) $PN 13
J 0
(-3590 3810);
DISPLAY 0.808511 (-3590 3810);
PAINT ORANGE (-3590 3810);
FORCEPROP 2 LASTPIN (-3600 3750) $PN 14
J 0
(-3590 3760);
DISPLAY 0.808511 (-3590 3760);
PAINT ORANGE (-3590 3760);
FORCEPROP 2 LASTPIN (-4300 3600) $PN 5
J 2
(-4310 3610);
DISPLAY 0.808511 (-4310 3610);
PAINT ORANGE (-4310 3610);
FORCEPROP 1 LAST PACK_TYPE DISCRET-GC1
J 0
(-3950 3675);
DISPLAY 0.617021 (-3950 3675);
PAINT GREEN (-3950 3675);
DISPLAY INVISIBLE (-3950 3675);
FORCEPROP 2 LAST SEC 1
J 0
(-4150 4200);
DISPLAY 0.680851 (-4150 4200);
PAINT MONO (-4150 4200);
DISPLAY INVISIBLE (-4150 4200);
FORCEPROP 2 LAST SEC_TYPE DISCRET-GC1
J 0
(-4150 4200);
DISPLAY 1.021277 (-4150 4200);
PAINT ORANGE (-4150 4200);
DISPLAY INVISIBLE (-4150 4200);
FORCEPROP 1 LAST PART_NUMBER 071.09555.000W
J 0
(-3950 3675);
DISPLAY 0.617021 (-3950 3675);
PAINT GREEN (-3950 3675);
DISPLAY INVISIBLE (-3950 3675);
FORCEPROP 2 LAST CDS_LIB w_hdl
J 0
(-3950 3675);
PAINT MONO (-3950 3675);
DISPLAY INVISIBLE (-3950 3675);
FORCEPROP 1 LAST PATH I120
J 0
(-3950 3675);
DISPLAY 0.617021 (-3950 3675);
PAINT GREEN (-3950 3675);
DISPLAY INVISIBLE (-3950 3675);
FORCEPROP 1 LAST CDS_LMAN_SYM_OUTLINE -200,475,200,-475
J 0
(-3950 3675);
DISPLAY 0.468085 (-3950 3675);
PAINT GREEN (-3950 3675);
DISPLAY INVISIBLE (-3950 3675);
FORCEADD GND..1
(-3550 3225);
FORCEPROP 3 LASTPIN (-3550 3275) SIG_NAME GND\g
J 0
(-3540 3285);
DISPLAY 0.659574 (-3540 3285);
PAINT MONO (-3540 3285);
DISPLAY INVISIBLE (-3540 3285);
FORCEPROP 1 LAST PATH I121
J 0
(-3475 3225);
DISPLAY 0.872340 (-3475 3225);
PAINT AQUA (-3475 3225);
DISPLAY INVISIBLE (-3475 3225);
FORCEPROP 1 LAST VOLTAGE 0.0V
J 0
(-3595 3182);
DISPLAY 0.340426 (-3595 3182);
PAINT GREEN (-3595 3182);
DISPLAY INVISIBLE (-3595 3182);
FORCEPROP 1 LAST SIZE 1B
J 0
(-3475 3175);
DISPLAY 0.872340 (-3475 3175);
PAINT AQUA (-3475 3175);
DISPLAY INVISIBLE (-3475 3175);
FORCEPROP 2 LAST CDS_LIB mstr_symbols
J 0
(-3550 3225);
PAINT MONO (-3550 3225);
DISPLAY INVISIBLE (-3550 3225);
FORCEPROP 1 LAST BODY_TYPE PLUMBING
J 0
(-3595 3182);
DISPLAY 0.340426 (-3595 3182);
PAINT GREEN (-3595 3182);
DISPLAY INVISIBLE (-3595 3182);
FORCEPROP 1 LAST HDL_POWER GND
J 0
(-3550 3375);
DISPLAY 0.872340 (-3550 3375);
PAINT GREEN (-3550 3375);
DISPLAY INVISIBLE (-3550 3375);
FORCEADD OFFPAGE..2
(-2600 3800);
FORCEPROP 2 LAST $XR3 190 
J 0
(-2051 3800);
DISPLAY 0.638298 (-2051 3800);
PAINT MONO (-2051 3800);
FORCEPROP 2 LAST $XR2 175 
J 0
(-2171 3800);
DISPLAY 0.638298 (-2171 3800);
PAINT MONO (-2171 3800);
FORCEPROP 2 LAST $XR1 155 
J 0
(-2291 3800);
DISPLAY 0.638298 (-2291 3800);
PAINT MONO (-2291 3800);
FORCEPROP 2 LAST $XR0 111 
J 0
(-2411 3800);
DISPLAY 0.638298 (-2411 3800);
PAINT MONO (-2411 3800);
FORCEPROP 1 LAST COMMENT_BODY TRUE
J 0
(-2645 3705);
DISPLAY 0.872340 (-2645 3705);
PAINT GREEN (-2645 3705);
DISPLAY INVISIBLE (-2645 3705);
FORCEPROP 1 LAST OFFPAGE TRUE
J 0
(-2275 3675);
DISPLAY 0.872340 (-2275 3675);
PAINT GREEN (-2275 3675);
DISPLAY INVISIBLE (-2275 3675);
FORCEPROP 2 LAST PATH I122
J 0
(-2050 3850);
DISPLAY 1.021277 (-2050 3850);
PAINT ORANGE (-2050 3850);
DISPLAY INVISIBLE (-2050 3850);
FORCEPROP 2 LAST CDS_LIB mstr_standard
J 0
(-2600 3800);
PAINT MONO (-2600 3800);
DISPLAY INVISIBLE (-2600 3800);
FORCEADD OFFPAGE..2
(-2600 3750);
FORCEPROP 2 LAST $XR0 175 
J 0
(-2411 3750);
DISPLAY 0.638298 (-2411 3750);
PAINT MONO (-2411 3750);
FORCEPROP 1 LAST COMMENT_BODY TRUE
J 0
(-2645 3655);
DISPLAY 0.872340 (-2645 3655);
PAINT GREEN (-2645 3655);
DISPLAY INVISIBLE (-2645 3655);
FORCEPROP 1 LAST OFFPAGE TRUE
J 0
(-2275 3625);
DISPLAY 0.872340 (-2275 3625);
PAINT GREEN (-2275 3625);
DISPLAY INVISIBLE (-2275 3625);
FORCEPROP 2 LAST PATH I123
J 0
(-2400 3800);
DISPLAY 1.021277 (-2400 3800);
PAINT ORANGE (-2400 3800);
DISPLAY INVISIBLE (-2400 3800);
FORCEPROP 2 LAST CDS_LIB mstr_standard
J 0
(-2600 3750);
PAINT MONO (-2600 3750);
DISPLAY INVISIBLE (-2600 3750);
FORCEADD OFFPAGE..4
(-2600 3700);
FORCEPROP 2 LAST $XR3 144 
J 0
(-2054 3700);
DISPLAY 0.638298 (-2054 3700);
PAINT MONO (-2054 3700);
FORCEPROP 2 LAST $XR2 118 
J 0
(-2174 3700);
DISPLAY 0.638298 (-2174 3700);
PAINT MONO (-2174 3700);
FORCEPROP 2 LAST $XR1 191 
J 0
(-2294 3700);
DISPLAY 0.638298 (-2294 3700);
PAINT MONO (-2294 3700);
FORCEPROP 2 LAST $XR0 133 
J 0
(-2414 3700);
DISPLAY 0.638298 (-2414 3700);
PAINT MONO (-2414 3700);
FORCEPROP 1 LAST COMMENT_BODY TRUE
J 0
(-2625 3600);
DISPLAY 1.404255 (-2625 3600);
PAINT PEACH (-2625 3600);
DISPLAY INVISIBLE (-2625 3600);
FORCEPROP 1 LAST OFFPAGE TRUE
J 0
(-2275 3575);
PAINT GREEN (-2275 3575);
DISPLAY INVISIBLE (-2275 3575);
FORCEPROP 2 LAST PATH I124
J 0
(-2050 3750);
DISPLAY 1.021277 (-2050 3750);
PAINT ORANGE (-2050 3750);
DISPLAY INVISIBLE (-2050 3750);
FORCEPROP 2 LAST CDS_LIB mstr_standard
J 0
(-2600 3700);
PAINT ORANGE (-2600 3700);
DISPLAY INVISIBLE (-2600 3700);
FORCEADD OFFPAGE..4
(-2600 3650);
FORCEPROP 2 LAST $XR3 191 
J 0
(-2054 3650);
DISPLAY 0.638298 (-2054 3650);
PAINT MONO (-2054 3650);
FORCEPROP 2 LAST $XR2 139 
J 0
(-2174 3650);
DISPLAY 0.638298 (-2174 3650);
PAINT MONO (-2174 3650);
FORCEPROP 2 LAST $XR1 136 
J 0
(-2294 3650);
DISPLAY 0.638298 (-2294 3650);
PAINT MONO (-2294 3650);
FORCEPROP 2 LAST $XR0 119 
J 0
(-2414 3650);
DISPLAY 0.638298 (-2414 3650);
PAINT MONO (-2414 3650);
FORCEPROP 1 LAST COMMENT_BODY TRUE
J 0
(-2625 3550);
DISPLAY 1.404255 (-2625 3550);
PAINT PEACH (-2625 3550);
DISPLAY INVISIBLE (-2625 3550);
FORCEPROP 1 LAST OFFPAGE TRUE
J 0
(-2275 3525);
PAINT GREEN (-2275 3525);
DISPLAY INVISIBLE (-2275 3525);
FORCEPROP 2 LAST PATH I125
J 0
(-2050 3700);
DISPLAY 1.021277 (-2050 3700);
PAINT ORANGE (-2050 3700);
DISPLAY INVISIBLE (-2050 3700);
FORCEPROP 2 LAST CDS_LIB mstr_standard
J 0
(-2600 3650);
PAINT ORANGE (-2600 3650);
DISPLAY INVISIBLE (-2600 3650);
FORCEADD OFFPAGE..4
(-2600 3600);
FORCEPROP 2 LAST $XR4 191 
J 0
(-2414 3564);
DISPLAY 0.638298 (-2414 3564);
PAINT MONO (-2414 3564);
FORCEPROP 2 LAST $XR3 157 
J 0
(-2054 3600);
DISPLAY 0.638298 (-2054 3600);
PAINT MONO (-2054 3600);
FORCEPROP 2 LAST $XR2 118 
J 0
(-2174 3600);
DISPLAY 0.638298 (-2174 3600);
PAINT MONO (-2174 3600);
FORCEPROP 2 LAST $XR1 200 
J 0
(-2294 3600);
DISPLAY 0.638298 (-2294 3600);
PAINT MONO (-2294 3600);
FORCEPROP 2 LAST $XR0 196 
J 0
(-2414 3600);
DISPLAY 0.638298 (-2414 3600);
PAINT MONO (-2414 3600);
FORCEPROP 1 LAST COMMENT_BODY TRUE
J 0
(-2625 3500);
DISPLAY 1.404255 (-2625 3500);
PAINT PEACH (-2625 3500);
DISPLAY INVISIBLE (-2625 3500);
FORCEPROP 1 LAST OFFPAGE TRUE
J 0
(-2275 3475);
PAINT GREEN (-2275 3475);
DISPLAY INVISIBLE (-2275 3475);
FORCEPROP 2 LAST PATH I126
J 0
(-1675 3650);
DISPLAY 1.021277 (-1675 3650);
PAINT ORANGE (-1675 3650);
DISPLAY INVISIBLE (-1675 3650);
FORCEPROP 2 LAST CDS_LIB mstr_standard
J 0
(-2600 3600);
PAINT ORANGE (-2600 3600);
DISPLAY INVISIBLE (-2600 3600);
FORCEADD OFFPAGE..4
(-2600 3500);
FORCEPROP 2 LAST $XR2 190 
J 0
(-2174 3500);
DISPLAY 0.638298 (-2174 3500);
PAINT MONO (-2174 3500);
FORCEPROP 2 LAST $XR1 148 
J 0
(-2294 3500);
DISPLAY 0.638298 (-2294 3500);
PAINT MONO (-2294 3500);
FORCEPROP 2 LAST $XR0 118 
J 0
(-2414 3500);
DISPLAY 0.638298 (-2414 3500);
PAINT MONO (-2414 3500);
FORCEPROP 1 LAST COMMENT_BODY TRUE
J 0
(-2625 3400);
DISPLAY 1.404255 (-2625 3400);
PAINT PEACH (-2625 3400);
DISPLAY INVISIBLE (-2625 3400);
FORCEPROP 1 LAST OFFPAGE TRUE
J 0
(-2275 3375);
PAINT GREEN (-2275 3375);
DISPLAY INVISIBLE (-2275 3375);
FORCEPROP 2 LAST PATH I128
J 0
(-2150 3550);
DISPLAY 1.021277 (-2150 3550);
PAINT ORANGE (-2150 3550);
DISPLAY INVISIBLE (-2150 3550);
FORCEPROP 2 LAST CDS_LIB mstr_standard
J 0
(-2600 3500);
PAINT ORANGE (-2600 3500);
DISPLAY INVISIBLE (-2600 3500);
FORCEADD GND..1
(-5900 3450);
FORCEPROP 3 LASTPIN (-5900 3500) SIG_NAME GND\g
J 0
(-5890 3510);
DISPLAY 0.659574 (-5890 3510);
PAINT MONO (-5890 3510);
DISPLAY INVISIBLE (-5890 3510);
FORCEPROP 1 LAST HDL_POWER GND
J 0
(-5900 3600);
DISPLAY 0.872340 (-5900 3600);
PAINT GREEN (-5900 3600);
DISPLAY INVISIBLE (-5900 3600);
FORCEPROP 1 LAST BODY_TYPE PLUMBING
J 0
(-5945 3407);
DISPLAY 0.340426 (-5945 3407);
PAINT GREEN (-5945 3407);
DISPLAY INVISIBLE (-5945 3407);
FORCEPROP 1 LAST SIZE 1B
J 0
(-5825 3400);
DISPLAY 0.872340 (-5825 3400);
PAINT AQUA (-5825 3400);
DISPLAY INVISIBLE (-5825 3400);
FORCEPROP 2 LAST CDS_LIB mstr_symbols
J 0
(-5900 3450);
PAINT MONO (-5900 3450);
DISPLAY INVISIBLE (-5900 3450);
FORCEPROP 1 LAST VOLTAGE 0.0V
J 0
(-5945 3407);
DISPLAY 0.340426 (-5945 3407);
PAINT GREEN (-5945 3407);
DISPLAY INVISIBLE (-5945 3407);
FORCEPROP 1 LAST PATH I13
J 0
(-5825 3450);
DISPLAY 0.872340 (-5825 3450);
PAINT AQUA (-5825 3450);
DISPLAY INVISIBLE (-5825 3450);
FORCEADD OFFPAGE..6
(-5050 3650);
FORCEPROP 2 LAST $XR0 155 
J 0
(-5330 3650);
DISPLAY 0.638298 (-5330 3650);
PAINT MONO (-5330 3650);
FORCEPROP 1 LAST COMMENT_BODY TRUE
J 0
(-4950 3575);
DISPLAY 0.872340 (-4950 3575);
PAINT GREEN (-4950 3575);
DISPLAY INVISIBLE (-4950 3575);
FORCEPROP 1 LAST OFFPAGE TRUE
J 0
(-4725 3525);
DISPLAY 0.872340 (-4725 3525);
PAINT GREEN (-4725 3525);
DISPLAY INVISIBLE (-4725 3525);
FORCEPROP 2 LAST CDS_LIB mstr_standard
J 0
(-5050 3650);
PAINT MONO (-5050 3650);
DISPLAY INVISIBLE (-5050 3650);
FORCEPROP 2 LAST PATH I138
J 0
(-5000 3725);
DISPLAY 1.021277 (-5000 3725);
PAINT ORANGE (-5000 3725);
DISPLAY INVISIBLE (-5000 3725);
FORCEADD OFFPAGE..6
(-5050 3600);
FORCEPROP 2 LAST $XR0 155 
J 0
(-5330 3600);
DISPLAY 0.638298 (-5330 3600);
PAINT MONO (-5330 3600);
FORCEPROP 1 LAST COMMENT_BODY TRUE
J 0
(-4950 3525);
DISPLAY 0.872340 (-4950 3525);
PAINT GREEN (-4950 3525);
DISPLAY INVISIBLE (-4950 3525);
FORCEPROP 1 LAST OFFPAGE TRUE
J 0
(-4725 3475);
DISPLAY 0.872340 (-4725 3475);
PAINT GREEN (-4725 3475);
DISPLAY INVISIBLE (-4725 3475);
FORCEPROP 2 LAST PATH I139
J 0
(-5000 3675);
DISPLAY 1.021277 (-5000 3675);
PAINT ORANGE (-5000 3675);
DISPLAY INVISIBLE (-5000 3675);
FORCEPROP 2 LAST CDS_LIB mstr_standard
J 0
(-5050 3600);
PAINT MONO (-5050 3600);
DISPLAY INVISIBLE (-5050 3600);
FORCEADD OFFPAGE..6
(-5050 3550);
FORCEPROP 2 LAST $XR0 155 
J 0
(-5330 3550);
DISPLAY 0.638298 (-5330 3550);
PAINT MONO (-5330 3550);
FORCEPROP 1 LAST COMMENT_BODY TRUE
J 0
(-4950 3475);
DISPLAY 0.872340 (-4950 3475);
PAINT GREEN (-4950 3475);
DISPLAY INVISIBLE (-4950 3475);
FORCEPROP 1 LAST OFFPAGE TRUE
J 0
(-4725 3425);
DISPLAY 0.872340 (-4725 3425);
PAINT GREEN (-4725 3425);
DISPLAY INVISIBLE (-4725 3425);
FORCEPROP 2 LAST PATH I140
J 0
(-5000 3625);
DISPLAY 1.021277 (-5000 3625);
PAINT ORANGE (-5000 3625);
DISPLAY INVISIBLE (-5000 3625);
FORCEPROP 2 LAST CDS_LIB mstr_standard
J 0
(-5050 3550);
PAINT MONO (-5050 3550);
DISPLAY INVISIBLE (-5050 3550);
FORCEADD OFFPAGE..6
(-5050 3500);
FORCEPROP 2 LAST $XR0 155 
J 0
(-5330 3500);
DISPLAY 0.638298 (-5330 3500);
PAINT MONO (-5330 3500);
FORCEPROP 1 LAST COMMENT_BODY TRUE
J 0
(-4950 3425);
DISPLAY 0.872340 (-4950 3425);
PAINT GREEN (-4950 3425);
DISPLAY INVISIBLE (-4950 3425);
FORCEPROP 1 LAST OFFPAGE TRUE
J 0
(-4725 3375);
DISPLAY 0.872340 (-4725 3375);
PAINT GREEN (-4725 3375);
DISPLAY INVISIBLE (-4725 3375);
FORCEPROP 2 LAST PATH I141
J 0
(-5000 3575);
DISPLAY 1.021277 (-5000 3575);
PAINT ORANGE (-5000 3575);
DISPLAY INVISIBLE (-5000 3575);
FORCEPROP 2 LAST CDS_LIB mstr_standard
J 0
(-5050 3500);
PAINT MONO (-5050 3500);
DISPLAY INVISIBLE (-5050 3500);
FORCEADD OFFPAGE..6
(-5050 3450);
FORCEPROP 2 LAST $XR0 155 
J 0
(-5330 3450);
DISPLAY 0.638298 (-5330 3450);
PAINT MONO (-5330 3450);
FORCEPROP 1 LAST COMMENT_BODY TRUE
J 0
(-4950 3375);
DISPLAY 0.872340 (-4950 3375);
PAINT GREEN (-4950 3375);
DISPLAY INVISIBLE (-4950 3375);
FORCEPROP 1 LAST OFFPAGE TRUE
J 0
(-4725 3325);
DISPLAY 0.872340 (-4725 3325);
PAINT GREEN (-4725 3325);
DISPLAY INVISIBLE (-4725 3325);
FORCEPROP 2 LAST PATH I142
J 0
(-5000 3525);
DISPLAY 1.021277 (-5000 3525);
PAINT ORANGE (-5000 3525);
DISPLAY INVISIBLE (-5000 3525);
FORCEPROP 2 LAST CDS_LIB mstr_standard
J 0
(-5050 3450);
PAINT MONO (-5050 3450);
DISPLAY INVISIBLE (-5050 3450);
FORCEADD OFFPAGE..6
(-5050 3400);
FORCEPROP 2 LAST $XR0 155 
J 0
(-5330 3400);
DISPLAY 0.638298 (-5330 3400);
PAINT MONO (-5330 3400);
FORCEPROP 1 LAST COMMENT_BODY TRUE
J 0
(-4950 3325);
DISPLAY 0.872340 (-4950 3325);
PAINT GREEN (-4950 3325);
DISPLAY INVISIBLE (-4950 3325);
FORCEPROP 1 LAST OFFPAGE TRUE
J 0
(-4725 3275);
DISPLAY 0.872340 (-4725 3275);
PAINT GREEN (-4725 3275);
DISPLAY INVISIBLE (-4725 3275);
FORCEPROP 2 LAST PATH I143
J 0
(-5000 3475);
DISPLAY 1.021277 (-5000 3475);
PAINT ORANGE (-5000 3475);
DISPLAY INVISIBLE (-5000 3475);
FORCEPROP 2 LAST CDS_LIB mstr_standard
J 0
(-5050 3400);
PAINT MONO (-5050 3400);
DISPLAY INVISIBLE (-5050 3400);
FORCEADD OFFPAGE..6
(-5050 3350);
FORCEPROP 2 LAST $XR0 155 
J 0
(-5330 3350);
DISPLAY 0.638298 (-5330 3350);
PAINT MONO (-5330 3350);
FORCEPROP 1 LAST COMMENT_BODY TRUE
J 0
(-4950 3275);
DISPLAY 0.872340 (-4950 3275);
PAINT GREEN (-4950 3275);
DISPLAY INVISIBLE (-4950 3275);
FORCEPROP 1 LAST OFFPAGE TRUE
J 0
(-4725 3225);
DISPLAY 0.872340 (-4725 3225);
PAINT GREEN (-4725 3225);
DISPLAY INVISIBLE (-4725 3225);
FORCEPROP 2 LAST PATH I144
J 0
(-5000 3425);
DISPLAY 1.021277 (-5000 3425);
PAINT ORANGE (-5000 3425);
DISPLAY INVISIBLE (-5000 3425);
FORCEPROP 2 LAST CDS_LIB mstr_standard
J 0
(-5050 3350);
PAINT MONO (-5050 3350);
DISPLAY INVISIBLE (-5050 3350);
FORCEADD OFFPAGE..6
(-5050 3300);
FORCEPROP 2 LAST $XR0 155 
J 0
(-5330 3300);
DISPLAY 0.638298 (-5330 3300);
PAINT MONO (-5330 3300);
FORCEPROP 1 LAST COMMENT_BODY TRUE
J 0
(-4950 3225);
DISPLAY 0.872340 (-4950 3225);
PAINT GREEN (-4950 3225);
DISPLAY INVISIBLE (-4950 3225);
FORCEPROP 1 LAST OFFPAGE TRUE
J 0
(-4725 3175);
DISPLAY 0.872340 (-4725 3175);
PAINT GREEN (-4725 3175);
DISPLAY INVISIBLE (-4725 3175);
FORCEPROP 2 LAST PATH I145
J 0
(-5000 3375);
DISPLAY 1.021277 (-5000 3375);
PAINT ORANGE (-5000 3375);
DISPLAY INVISIBLE (-5000 3375);
FORCEPROP 2 LAST CDS_LIB mstr_standard
J 0
(-5050 3300);
PAINT MONO (-5050 3300);
DISPLAY INVISIBLE (-5050 3300);
FORCEADD OFFPAGE..4
(-2600 3900);
FORCEPROP 2 LAST $XR2 247 
J 0
(-2144 3900);
DISPLAY 0.638298 (-2144 3900);
PAINT MONO (-2144 3900);
FORCEPROP 2 LAST $XR1 176 
J 0
(-2264 3900);
DISPLAY 0.638298 (-2264 3900);
PAINT MONO (-2264 3900);
FORCEPROP 2 LAST $XR0 145 
J 0
(-2384 3900);
DISPLAY 0.638298 (-2384 3900);
PAINT MONO (-2384 3900);
FORCEPROP 1 LAST COMMENT_BODY TRUE
J 0
(-2625 3800);
DISPLAY 1.404255 (-2625 3800);
PAINT PEACH (-2625 3800);
DISPLAY INVISIBLE (-2625 3800);
FORCEPROP 1 LAST OFFPAGE TRUE
J 0
(-2275 3775);
PAINT GREEN (-2275 3775);
DISPLAY INVISIBLE (-2275 3775);
FORCEPROP 2 LAST CDS_LIB mstr_standard
J 0
(-2600 3900);
PAINT MONO (-2600 3900);
DISPLAY INVISIBLE (-2600 3900);
FORCEPROP 2 LAST PATH I146
J 0
(-2425 3975);
DISPLAY 1.021277 (-2425 3975);
PAINT ORANGE (-2425 3975);
DISPLAY INVISIBLE (-2425 3975);
FORCEADD OFFPAGE..3
(-2600 3950);
FORCEPROP 2 LAST $XR2 247 
J 0
(-2146 3950);
DISPLAY 0.638298 (-2146 3950);
PAINT MONO (-2146 3950);
FORCEPROP 2 LAST $XR1 176 
J 0
(-2266 3950);
DISPLAY 0.638298 (-2266 3950);
PAINT MONO (-2266 3950);
FORCEPROP 2 LAST $XR0 145 
J 0
(-2386 3950);
DISPLAY 0.638298 (-2386 3950);
PAINT MONO (-2386 3950);
FORCEPROP 1 LAST COMMENT_BODY TRUE
J 0
(-2650 3850);
DISPLAY 0.872340 (-2650 3850);
PAINT GREEN (-2650 3850);
DISPLAY INVISIBLE (-2650 3850);
FORCEPROP 1 LAST OFFPAGE TRUE
J 0
(-2275 3825);
DISPLAY 0.872340 (-2275 3825);
PAINT GREEN (-2275 3825);
DISPLAY INVISIBLE (-2275 3825);
FORCEPROP 2 LAST CDS_LIB mstr_standard
J 0
(-2600 3950);
PAINT MONO (-2600 3950);
DISPLAY INVISIBLE (-2600 3950);
FORCEPROP 2 LAST PATH I147
J 0
(-2400 4025);
DISPLAY 1.021277 (-2400 4025);
PAINT ORANGE (-2400 4025);
DISPLAY INVISIBLE (-2400 4025);
FORCEADD P3V3_STBY..1
(-5200 4450);
FORCEPROP 3 LASTPIN (-5200 4400) SIG_NAME P3V3_STBY\g
J 0
(-5190 4410);
DISPLAY 0.659574 (-5190 4410);
PAINT MONO (-5190 4410);
DISPLAY INVISIBLE (-5190 4410);
FORCEPROP 1 LAST HDL_POWER P3V3_STBY
J 0
(-5500 4325);
DISPLAY 0.872340 (-5500 4325);
PAINT ORANGE (-5500 4325);
DISPLAY INVISIBLE (-5500 4325);
FORCEPROP 1 LAST BODY_TYPE PLUMBING
J 0
(-5245 4407);
DISPLAY 0.340426 (-5245 4407);
PAINT GREEN (-5245 4407);
DISPLAY INVISIBLE (-5245 4407);
FORCEPROP 1 LAST PATH I148
J 0
(-5155 4452);
DISPLAY 0.340426 (-5155 4452);
PAINT GREEN (-5155 4452);
DISPLAY INVISIBLE (-5155 4452);
FORCEPROP 1 LAST VOLTAGE 3.3V
J 0
(-5245 4407);
DISPLAY 0.340426 (-5245 4407);
PAINT GREEN (-5245 4407);
DISPLAY INVISIBLE (-5245 4407);
FORCEPROP 1 LAST SIZE 1B
J 0
(-5155 4472);
DISPLAY 0.340426 (-5155 4472);
PAINT GREEN (-5155 4472);
DISPLAY INVISIBLE (-5155 4472);
FORCEPROP 2 LAST CDS_LIB mstr_symbols
J 0
(-5200 4450);
PAINT MONO (-5200 4450);
DISPLAY INVISIBLE (-5200 4450);
FORCEADD GND..1
(-5200 4000);
FORCEPROP 3 LASTPIN (-5200 4050) SIG_NAME GND\g
J 0
(-5190 4060);
DISPLAY 0.659574 (-5190 4060);
PAINT MONO (-5190 4060);
DISPLAY INVISIBLE (-5190 4060);
FORCEPROP 1 LAST HDL_POWER GND
J 0
(-5200 4150);
DISPLAY 1.170213 (-5200 4150);
PAINT GREEN (-5200 4150);
DISPLAY INVISIBLE (-5200 4150);
FORCEPROP 1 LAST BODY_TYPE PLUMBING
J 0
(-5245 3957);
DISPLAY 0.340426 (-5245 3957);
PAINT GREEN (-5245 3957);
DISPLAY INVISIBLE (-5245 3957);
FORCEPROP 2 LAST CDS_LIB mstr_symbols
J 0
(-5200 4000);
PAINT MONO (-5200 4000);
DISPLAY INVISIBLE (-5200 4000);
FORCEPROP 1 LAST SIZE 1B
J 0
(-5125 3950);
DISPLAY 1.170213 (-5125 3950);
PAINT AQUA (-5125 3950);
DISPLAY INVISIBLE (-5125 3950);
FORCEPROP 1 LAST VOLTAGE 0.0V
J 0
(-5245 3957);
DISPLAY 0.340426 (-5245 3957);
PAINT GREEN (-5245 3957);
DISPLAY INVISIBLE (-5245 3957);
FORCEPROP 1 LAST PATH I150
J 0
(-5125 4000);
DISPLAY 0.872340 (-5125 4000);
PAINT AQUA (-5125 4000);
DISPLAY INVISIBLE (-5125 4000);
FORCEADD CAP_A..1
(-5200 4200);
FORCEPROP 1 LAST LOCATION C6W1
J 0
(-5150 4300);
DISPLAY 0.617021 (-5150 4300);
PAINT AQUA (-5150 4300);
FORCEPROP 1 LASTPIN (-5200 4100) $PN 2
J 0
(-5190 4080);
DISPLAY 0.617021 (-5190 4080);
PAINT ORANGE (-5190 4080);
FORCEPROP 1 LASTPIN (-5200 4300) $PN 1
J 0
(-5190 4280);
DISPLAY 0.617021 (-5190 4280);
PAINT ORANGE (-5190 4280);
FORCEPROP 1 LAST VALUE 0.1UF
J 0
(-5150 4250);
DISPLAY 0.617021 (-5150 4250);
PAINT SKYBLUE (-5150 4250);
FORCEPROP 1 LAST VOLTAGE 16V
J 0
(-5150 4200);
DISPLAY 0.617021 (-5150 4200);
PAINT SKYBLUE (-5150 4200);
FORCEPROP 1 LAST TOLERANCE 10%
J 0
(-5150 4150);
DISPLAY 0.617021 (-5150 4150);
PAINT SKYBLUE (-5150 4150);
FORCEPROP 1 LAST MATERIAL X7R
J 0
(-5150 4100);
DISPLAY 0.617021 (-5150 4100);
PAINT SKYBLUE (-5150 4100);
FORCEPROP 1 LAST PART_NUMBER A36096-030
J 0
(-5150 4050);
DISPLAY 0.617021 (-5150 4050);
PAINT BLUE (-5150 4050);
FORCEPROP 1 LAST PACK_TYPE 0402V
J 0
(-5150 4000);
DISPLAY 0.617021 (-5150 4000);
PAINT SKYBLUE (-5150 4000);
FORCEPROP 1 LAST PATH I151
J 0
(-5150 4350);
DISPLAY 0.978723 (-5150 4350);
PAINT WHITE (-5150 4350);
DISPLAY INVISIBLE (-5150 4350);
FORCEPROP 2 LAST CDS_LIB dev_discrete
J 0
(-5200 4200);
PAINT ORANGE (-5200 4200);
DISPLAY INVISIBLE (-5200 4200);
FORCEPROP 2 LAST CDS_SEC 1
J 0
(-5150 4350);
PAINT ORANGE (-5150 4350);
DISPLAY INVISIBLE (-5150 4350);
FORCEPROP 2 LAST ROOM VDDQ_KLM_PWR_VR
J 0
(-5150 4350);
DISPLAY 1.361702 (-5150 4350);
PAINT ORANGE (-5150 4350);
DISPLAY INVISIBLE (-5150 4350);
FORCEPROP 2 LAST SEC_TYPE 0402V
J 0
(-5150 4425);
DISPLAY 1.021277 (-5150 4425);
PAINT ORANGE (-5150 4425);
DISPLAY INVISIBLE (-5150 4425);
FORCEPROP 2 LAST SEC 1
J 0
(-5150 4425);
DISPLAY 0.680851 (-5150 4425);
PAINT MONO (-5150 4425);
DISPLAY INVISIBLE (-5150 4425);
FORCEPROP 2 LAST CDS_LOCATION C6W1
J 0
(-5150 4300);
DISPLAY 0.617021 (-5150 4300);
PAINT AQUA (-5150 4300);
DISPLAY INVISIBLE (-5150 4300);
FORCEADD OFFPAGE..4
(-450 3450);
FORCEPROP 2 LAST $XR3 190 
J 0
(-264 3378);
DISPLAY 0.638298 (-264 3378);
PAINT MONO (-264 3378);
FORCEPROP 2 LAST $XR2 120 
J 0
(-264 3486);
DISPLAY 0.638298 (-264 3486);
PAINT MONO (-264 3486);
FORCEPROP 2 LAST $XR1 147 
J 0
(-264 3414);
DISPLAY 0.638298 (-264 3414);
PAINT MONO (-264 3414);
FORCEPROP 2 LAST $XR0 92 
J 0
(-264 3450);
DISPLAY 0.638298 (-264 3450);
PAINT MONO (-264 3450);
FORCEPROP 1 LAST COMMENT_BODY TRUE
J 0
(-475 3350);
DISPLAY 1.404255 (-475 3350);
PAINT PEACH (-475 3350);
DISPLAY INVISIBLE (-475 3350);
FORCEPROP 1 LAST OFFPAGE TRUE
J 0
(-125 3325);
PAINT GREEN (-125 3325);
DISPLAY INVISIBLE (-125 3325);
FORCEPROP 2 LAST PATH I152
J 0
(75 3500);
DISPLAY 1.021277 (75 3500);
PAINT ORANGE (75 3500);
DISPLAY INVISIBLE (75 3500);
FORCEPROP 2 LAST CDS_LIB mstr_standard
J 0
(-450 3450);
PAINT MONO (-450 3450);
DISPLAY INVISIBLE (-450 3450);
FORCEADD OFFPAGE..4
(-450 3650);
FORCEPROP 2 LAST $XR2 190 
J 0
(-264 3686);
DISPLAY 0.638298 (-264 3686);
PAINT MONO (-264 3686);
FORCEPROP 2 LAST $XR1 144 
J 0
(-264 3614);
DISPLAY 0.638298 (-264 3614);
PAINT MONO (-264 3614);
FORCEPROP 2 LAST $XR0 92 
J 0
(-264 3650);
DISPLAY 0.638298 (-264 3650);
PAINT MONO (-264 3650);
FORCEPROP 1 LAST COMMENT_BODY TRUE
J 0
(-475 3550);
DISPLAY 1.404255 (-475 3550);
PAINT PEACH (-475 3550);
DISPLAY INVISIBLE (-475 3550);
FORCEPROP 1 LAST OFFPAGE TRUE
J 0
(-125 3525);
PAINT GREEN (-125 3525);
DISPLAY INVISIBLE (-125 3525);
FORCEPROP 2 LAST CDS_LIB mstr_standard
J 0
(-450 3650);
PAINT ORANGE (-450 3650);
DISPLAY INVISIBLE (-450 3650);
FORCEPROP 2 LAST PATH I153
J 0
(-50 3700);
DISPLAY 1.021277 (-50 3700);
PAINT ORANGE (-50 3700);
DISPLAY INVISIBLE (-50 3700);
FORCEADD OFFPAGE..4
(-2600 3450);
FORCEPROP 2 LAST $XR1 168 
J 0
(-2414 3414);
DISPLAY 0.638298 (-2414 3414);
PAINT MONO (-2414 3414);
FORCEPROP 2 LAST $XR0 155 
J 0
(-2414 3450);
DISPLAY 0.638298 (-2414 3450);
PAINT MONO (-2414 3450);
FORCEPROP 1 LAST COMMENT_BODY TRUE
J 0
(-2625 3350);
DISPLAY 1.404255 (-2625 3350);
PAINT PEACH (-2625 3350);
DISPLAY INVISIBLE (-2625 3350);
FORCEPROP 1 LAST OFFPAGE TRUE
J 0
(-2275 3325);
PAINT GREEN (-2275 3325);
DISPLAY INVISIBLE (-2275 3325);
FORCEPROP 2 LAST CDS_LIB mstr_standard
J 0
(-2600 3450);
PAINT ORANGE (-2600 3450);
DISPLAY INVISIBLE (-2600 3450);
FORCEPROP 2 LAST PATH I154
J 0
(-2150 3500);
DISPLAY 1.021277 (-2150 3500);
PAINT ORANGE (-2150 3500);
DISPLAY INVISIBLE (-2150 3500);
FORCEADD P3V3_STBY..1
(-1750 3950);
FORCEPROP 3 LASTPIN (-1750 3900) SIG_NAME P3V3_STBY\g
J 0
(-1740 3910);
DISPLAY 0.659574 (-1740 3910);
PAINT MONO (-1740 3910);
DISPLAY INVISIBLE (-1740 3910);
FORCEPROP 1 LAST HDL_POWER P3V3_STBY
J 0
(-2050 3825);
DISPLAY 0.872340 (-2050 3825);
PAINT ORANGE (-2050 3825);
DISPLAY INVISIBLE (-2050 3825);
FORCEPROP 1 LAST BODY_TYPE PLUMBING
J 0
(-1795 3907);
DISPLAY 0.340426 (-1795 3907);
PAINT GREEN (-1795 3907);
DISPLAY INVISIBLE (-1795 3907);
FORCEPROP 1 LAST PATH I156
J 0
(-1705 3952);
DISPLAY 0.340426 (-1705 3952);
PAINT GREEN (-1705 3952);
DISPLAY INVISIBLE (-1705 3952);
FORCEPROP 1 LAST VOLTAGE 3.3V
J 0
(-1795 3907);
DISPLAY 0.340426 (-1795 3907);
PAINT GREEN (-1795 3907);
DISPLAY INVISIBLE (-1795 3907);
FORCEPROP 1 LAST SIZE 1B
J 0
(-1705 3972);
DISPLAY 0.340426 (-1705 3972);
PAINT GREEN (-1705 3972);
DISPLAY INVISIBLE (-1705 3972);
FORCEPROP 2 LAST CDS_LIB mstr_symbols
J 0
(-1750 3950);
PAINT MONO (-1750 3950);
DISPLAY INVISIBLE (-1750 3950);
FORCEADD DIODE..1
R 6
(-1350 3650);
FORCEPROP 1 LASTPIN (-1450 3650) $PN 2
J 2
(-1415 3611);
DISPLAY 0.617021 (-1415 3611);
PAINT AQUA (-1415 3611);
FORCEPROP 1 LAST VALUE BAT54WS
J 0
(-1300 3771);
DISPLAY 0.617021 (-1300 3771);
PAINT SKYBLUE (-1300 3771);
FORCEPROP 1 LAST MATERIAL IC
J 0
(-1400 3774);
DISPLAY 0.617021 (-1400 3774);
PAINT SKYBLUE (-1400 3774);
FORCEPROP 1 LAST LOCATION CR6W1
J 0
(-1552 3765);
DISPLAY 0.617021 (-1552 3765);
PAINT AQUA (-1552 3765);
FORCEPROP 1 LAST PART_NUMBER C73510-001
J 0
(-1400 3721);
DISPLAY 0.617021 (-1400 3721);
PAINT BLUE (-1400 3721);
FORCEPROP 1 LASTPIN (-1250 3650) $PN 1
J 0
(-1285 3611);
DISPLAY 0.617021 (-1285 3611);
PAINT AQUA (-1285 3611);
FORCEPROP 1 LAST PACK_TYPE SMLF
J 0
(-1550 3711);
DISPLAY 0.617021 (-1550 3711);
PAINT SKYBLUE (-1550 3711);
FORCEPROP 2 LAST CDS_LOCATION CR6W1
J 0
(-1377 3465);
DISPLAY 0.617021 (-1377 3465);
PAINT AQUA (-1377 3465);
DISPLAY INVISIBLE (-1377 3465);
FORCEPROP 2 LAST SEC 1
J 2
(-1375 3343);
DISPLAY 0.680851 (-1375 3343);
PAINT MONO (-1375 3343);
DISPLAY INVISIBLE (-1375 3343);
FORCEPROP 2 LAST SEC_TYPE SMLF
J 2
(-1375 3327);
DISPLAY 1.021277 (-1375 3327);
PAINT ORANGE (-1375 3327);
DISPLAY INVISIBLE (-1375 3327);
FORCEPROP 2 LAST CDS_LIB mstr_discrete
J 0
(-1350 3603);
PAINT ORANGE (-1350 3603);
DISPLAY INVISIBLE (-1350 3603);
FORCEPROP 1 LAST PATH I157
J 0
(-1370 3394);
DISPLAY 0.978723 (-1370 3394);
PAINT PINK (-1370 3394);
DISPLAY INVISIBLE (-1370 3394);
FORCEADD DIODE..1
R 6
(-1350 3450);
FORCEPROP 1 LASTPIN (-1250 3450) $PN 1
J 0
(-1285 3411);
DISPLAY 0.617021 (-1285 3411);
PAINT AQUA (-1285 3411);
FORCEPROP 1 LAST MATERIAL IC
J 0
(-1425 3374);
DISPLAY 0.617021 (-1425 3374);
PAINT SKYBLUE (-1425 3374);
FORCEPROP 1 LAST PACK_TYPE SMLF
J 0
(-1575 3311);
DISPLAY 0.617021 (-1575 3311);
PAINT SKYBLUE (-1575 3311);
FORCEPROP 1 LAST VALUE BAT54WS
J 0
(-1325 3371);
DISPLAY 0.617021 (-1325 3371);
PAINT SKYBLUE (-1325 3371);
FORCEPROP 1 LAST PART_NUMBER C73510-001
J 0
(-1425 3321);
DISPLAY 0.617021 (-1425 3321);
PAINT BLUE (-1425 3321);
FORCEPROP 1 LAST LOCATION CR6W2
J 0
(-1577 3365);
DISPLAY 0.617021 (-1577 3365);
PAINT AQUA (-1577 3365);
FORCEPROP 1 LASTPIN (-1450 3450) $PN 2
J 2
(-1415 3411);
DISPLAY 0.617021 (-1415 3411);
PAINT AQUA (-1415 3411);
FORCEPROP 2 LAST CDS_LOCATION CR6W2
J 0
(-1377 3265);
DISPLAY 0.617021 (-1377 3265);
PAINT AQUA (-1377 3265);
DISPLAY INVISIBLE (-1377 3265);
FORCEPROP 2 LAST SEC 1
J 2
(-1375 3143);
DISPLAY 0.680851 (-1375 3143);
PAINT MONO (-1375 3143);
DISPLAY INVISIBLE (-1375 3143);
FORCEPROP 2 LAST SEC_TYPE SMLF
J 2
(-1375 3127);
DISPLAY 1.021277 (-1375 3127);
PAINT ORANGE (-1375 3127);
DISPLAY INVISIBLE (-1375 3127);
FORCEPROP 2 LAST CDS_LIB mstr_discrete
J 0
(-1350 3403);
PAINT ORANGE (-1350 3403);
DISPLAY INVISIBLE (-1350 3403);
FORCEPROP 1 LAST PATH I158
J 0
(-1370 3240);
DISPLAY 0.978723 (-1370 3240);
PAINT PINK (-1370 3240);
DISPLAY INVISIBLE (-1370 3240);
FORCEADD RES..2
R 2
(-6600 4200);
FORCEPROP 1 LASTPIN (-6600 4300) $PN 1
J 2
(-6605 4262);
DISPLAY 0.787234 (-6605 4262);
PAINT ORANGE (-6605 4262);
FORCEPROP 1 LAST VALUE 4.75K
J 0
(-6570 4275);
DISPLAY 0.617021 (-6570 4275);
PAINT SKYBLUE (-6570 4275);
FORCEPROP 1 LAST LOCATION R6W4
J 0
(-6570 4325);
DISPLAY 0.617021 (-6570 4325);
PAINT AQUA (-6570 4325);
FORCEPROP 1 LAST TOLERANCE 1%
J 0
(-6570 4225);
DISPLAY 0.617021 (-6570 4225);
PAINT SKYBLUE (-6570 4225);
FORCEPROP 1 LAST WATTAGE 1/16W
J 0
(-6565 4175);
DISPLAY 0.617021 (-6565 4175);
PAINT SKYBLUE (-6565 4175);
FORCEPROP 1 LAST PART_NUMBER G21796-072
J 0
(-6565 4075);
DISPLAY 0.617021 (-6565 4075);
PAINT BLUE (-6565 4075);
FORCEPROP 1 LASTPIN (-6600 4100) $PN 2
J 2
(-6605 4110);
DISPLAY 0.787234 (-6605 4110);
PAINT ORANGE (-6605 4110);
FORCEPROP 1 LAST MATERIAL CHIP
J 0
(-6565 4125);
DISPLAY 0.617021 (-6565 4125);
PAINT SKYBLUE (-6565 4125);
FORCEPROP 1 LAST PACK_TYPE 0402
J 0
(-6565 4025);
DISPLAY 0.617021 (-6565 4025);
PAINT SKYBLUE (-6565 4025);
FORCEPROP 1 LAST PATH I159
J 2
(-6650 4375);
DISPLAY 0.978723 (-6650 4375);
PAINT WHITE (-6650 4375);
DISPLAY INVISIBLE (-6650 4375);
FORCEPROP 2 LAST SEC_TYPE 0402
J 0
(-6650 4425);
DISPLAY 1.021277 (-6650 4425);
PAINT ORANGE (-6650 4425);
DISPLAY INVISIBLE (-6650 4425);
FORCEPROP 0 LAST SEC 1
J 0
(-6625 4375);
DISPLAY 0.680851 (-6625 4375);
PAINT MONO (-6625 4375);
DISPLAY INVISIBLE (-6625 4375);
FORCEPROP 0 LAST BOM_COST SM_THERM
J 0
(-6625 4525);
DISPLAY 1.021277 (-6625 4525);
PAINT ORANGE (-6625 4525);
DISPLAY INVISIBLE (-6625 4525);
FORCEPROP 0 LAST ROOM CPU_FANS
J 0
(-6625 4425);
DISPLAY 1.021277 (-6625 4425);
PAINT ORANGE (-6625 4425);
DISPLAY INVISIBLE (-6625 4425);
FORCEPROP 2 LAST CDS_LIB mstr_discrete
J 0
(-6600 4200);
PAINT MONO (-6600 4200);
DISPLAY INVISIBLE (-6600 4200);
FORCEADD RES..2
R 2
(-6250 4200);
FORCEPROP 1 LAST LOCATION R6W5
J 0
(-6220 4325);
DISPLAY 0.617021 (-6220 4325);
PAINT AQUA (-6220 4325);
FORCEPROP 1 LASTPIN (-6250 4300) $PN 1
J 2
(-6255 4262);
DISPLAY 0.787234 (-6255 4262);
PAINT ORANGE (-6255 4262);
FORCEPROP 1 LAST VALUE 4.75K
J 0
(-6220 4275);
DISPLAY 0.617021 (-6220 4275);
PAINT SKYBLUE (-6220 4275);
FORCEPROP 1 LAST TOLERANCE 1%
J 0
(-6220 4225);
DISPLAY 0.617021 (-6220 4225);
PAINT SKYBLUE (-6220 4225);
FORCEPROP 1 LAST WATTAGE 1/16W
J 0
(-6215 4175);
DISPLAY 0.617021 (-6215 4175);
PAINT SKYBLUE (-6215 4175);
FORCEPROP 1 LAST MATERIAL CHIP
J 0
(-6215 4125);
DISPLAY 0.617021 (-6215 4125);
PAINT SKYBLUE (-6215 4125);
FORCEPROP 1 LAST PART_NUMBER G21796-072
J 0
(-6215 4075);
DISPLAY 0.617021 (-6215 4075);
PAINT BLUE (-6215 4075);
FORCEPROP 1 LAST PACK_TYPE 0402
J 0
(-6215 4025);
DISPLAY 0.617021 (-6215 4025);
PAINT SKYBLUE (-6215 4025);
FORCEPROP 1 LASTPIN (-6250 4100) $PN 2
J 2
(-6255 4110);
DISPLAY 0.787234 (-6255 4110);
PAINT ORANGE (-6255 4110);
FORCEPROP 1 LAST PATH I160
J 2
(-6300 4375);
DISPLAY 0.978723 (-6300 4375);
PAINT WHITE (-6300 4375);
DISPLAY INVISIBLE (-6300 4375);
FORCEPROP 2 LAST SEC_TYPE 0402
J 0
(-6300 4425);
DISPLAY 1.021277 (-6300 4425);
PAINT ORANGE (-6300 4425);
DISPLAY INVISIBLE (-6300 4425);
FORCEPROP 0 LAST SEC 1
J 0
(-6275 4375);
DISPLAY 0.680851 (-6275 4375);
PAINT MONO (-6275 4375);
DISPLAY INVISIBLE (-6275 4375);
FORCEPROP 0 LAST BOM_COST SM_THERM
J 0
(-6275 4525);
DISPLAY 1.021277 (-6275 4525);
PAINT ORANGE (-6275 4525);
DISPLAY INVISIBLE (-6275 4525);
FORCEPROP 0 LAST ROOM CPU_FANS
J 0
(-6275 4425);
DISPLAY 1.021277 (-6275 4425);
PAINT ORANGE (-6275 4425);
DISPLAY INVISIBLE (-6275 4425);
FORCEPROP 2 LAST CDS_LIB mstr_discrete
J 0
(-6250 4200);
PAINT MONO (-6250 4200);
DISPLAY INVISIBLE (-6250 4200);
FORCEADD RES..2
R 2
(-5900 4200);
FORCEPROP 1 LAST PART_NUMBER G21796-072
J 0
(-5840 4075);
DISPLAY 0.617021 (-5840 4075);
PAINT BLUE (-5840 4075);
FORCEPROP 1 LAST LOCATION R6W6
J 0
(-5845 4325);
DISPLAY 0.617021 (-5845 4325);
PAINT AQUA (-5845 4325);
FORCEPROP 1 LAST WATTAGE 1/16W
J 0
(-5840 4175);
DISPLAY 0.617021 (-5840 4175);
PAINT SKYBLUE (-5840 4175);
FORCEPROP 1 LAST VALUE 4.75K
J 0
(-5845 4275);
DISPLAY 0.617021 (-5845 4275);
PAINT SKYBLUE (-5845 4275);
FORCEPROP 1 LAST PACK_TYPE 0402
J 0
(-5840 4025);
DISPLAY 0.617021 (-5840 4025);
PAINT SKYBLUE (-5840 4025);
FORCEPROP 1 LAST MATERIAL CHIP
J 0
(-5840 4125);
DISPLAY 0.617021 (-5840 4125);
PAINT SKYBLUE (-5840 4125);
FORCEPROP 1 LAST TOLERANCE 1%
J 0
(-5845 4225);
DISPLAY 0.617021 (-5845 4225);
PAINT SKYBLUE (-5845 4225);
FORCEPROP 1 LASTPIN (-5900 4300) $PN 1
J 2
(-5905 4262);
DISPLAY 0.787234 (-5905 4262);
PAINT ORANGE (-5905 4262);
FORCEPROP 1 LASTPIN (-5900 4100) $PN 2
J 2
(-5905 4110);
DISPLAY 0.787234 (-5905 4110);
PAINT ORANGE (-5905 4110);
FORCEPROP 1 LAST PATH I161
J 2
(-5950 4375);
DISPLAY 0.978723 (-5950 4375);
PAINT WHITE (-5950 4375);
DISPLAY INVISIBLE (-5950 4375);
FORCEPROP 2 LAST SEC_TYPE 0402
J 0
(-5950 4425);
DISPLAY 1.021277 (-5950 4425);
PAINT ORANGE (-5950 4425);
DISPLAY INVISIBLE (-5950 4425);
FORCEPROP 0 LAST SEC 1
J 0
(-5925 4375);
DISPLAY 0.680851 (-5925 4375);
PAINT MONO (-5925 4375);
DISPLAY INVISIBLE (-5925 4375);
FORCEPROP 0 LAST ROOM CPU_FANS
J 0
(-5925 4425);
DISPLAY 1.021277 (-5925 4425);
PAINT ORANGE (-5925 4425);
DISPLAY INVISIBLE (-5925 4425);
FORCEPROP 0 LAST BOM_COST SM_THERM
J 0
(-5925 4525);
DISPLAY 1.021277 (-5925 4525);
PAINT ORANGE (-5925 4525);
DISPLAY INVISIBLE (-5925 4525);
FORCEPROP 2 LAST CDS_LIB mstr_discrete
J 0
(-5900 4200);
PAINT MONO (-5900 4200);
DISPLAY INVISIBLE (-5900 4200);
FORCEADD RES..2
(-5900 3650);
FORCEPROP 1 LAST LOCATION R6W9
J 0
(-5855 3775);
DISPLAY 0.617021 (-5855 3775);
PAINT AQUA (-5855 3775);
FORCEPROP 1 LAST VALUE 4.75K
J 0
(-5855 3725);
DISPLAY 0.617021 (-5855 3725);
PAINT SKYBLUE (-5855 3725);
FORCEPROP 1 LAST PART_NUMBER G21796-072
J 0
(-5860 3525);
DISPLAY 0.617021 (-5860 3525);
PAINT BLUE (-5860 3525);
FORCEPROP 1 LAST PACK_TYPE 0402
J 0
(-5860 3475);
DISPLAY 0.617021 (-5860 3475);
PAINT SKYBLUE (-5860 3475);
FORCEPROP 1 LAST TOLERANCE 1%
J 0
(-5855 3675);
DISPLAY 0.617021 (-5855 3675);
PAINT SKYBLUE (-5855 3675);
FORCEPROP 1 LASTPIN (-5900 3750) $PN 1
J 0
(-5895 3712);
DISPLAY 0.787234 (-5895 3712);
PAINT ORANGE (-5895 3712);
FORCEPROP 1 LASTPIN (-5900 3550) $PN 2
J 0
(-5895 3560);
DISPLAY 0.787234 (-5895 3560);
PAINT ORANGE (-5895 3560);
FORCEPROP 1 LAST MATERIAL EMPTY
J 0
(-5860 3575);
DISPLAY 0.617021 (-5860 3575);
PAINT RED (-5860 3575);
FORCEPROP 1 LAST WATTAGE 1/16W
J 0
(-5860 3625);
DISPLAY 0.617021 (-5860 3625);
PAINT SKYBLUE (-5860 3625);
FORCEPROP 0 LAST CDS_LOCATION R6W9
J 0
(-5850 3825);
DISPLAY INVISIBLE (-5850 3825);
FORCEPROP 1 LAST PATH I162
J 0
(-5850 3825);
DISPLAY 0.978723 (-5850 3825);
PAINT WHITE (-5850 3825);
DISPLAY INVISIBLE (-5850 3825);
FORCEPROP 2 LAST CDS_LIB mstr_discrete
J 0
(-5900 3650);
PAINT MONO (-5900 3650);
DISPLAY INVISIBLE (-5900 3650);
FORCEPROP 0 LAST ROOM HOT_SWAP
J 0
(-5850 3875);
DISPLAY 1.021277 (-5850 3875);
PAINT ORANGE (-5850 3875);
DISPLAY INVISIBLE (-5850 3875);
FORCEPROP 0 LAST NO_XNET_CONNECTION 1
J 0
(-5850 3875);
PAINT MONO (-5850 3875);
DISPLAY INVISIBLE (-5850 3875);
FORCEPROP 0 LAST SEC 1
J 0
(-5850 3825);
DISPLAY 0.680851 (-5850 3825);
PAINT MONO (-5850 3825);
DISPLAY INVISIBLE (-5850 3825);
FORCEPROP 2 LAST SEC_TYPE 0402
J 0
(-5850 3875);
DISPLAY 1.021277 (-5850 3875);
PAINT ORANGE (-5850 3875);
DISPLAY INVISIBLE (-5850 3875);
FORCEPROP 0 LAST CDS_SEC 1
J 0
(-5850 3825);
DISPLAY INVISIBLE (-5850 3825);
FORCEADD RES..2
(-6250 3650);
FORCEPROP 1 LAST MATERIAL EMPTY
J 0
(-6210 3575);
DISPLAY 0.617021 (-6210 3575);
PAINT RED (-6210 3575);
FORCEPROP 1 LASTPIN (-6250 3550) $PN 2
J 0
(-6245 3560);
DISPLAY 0.787234 (-6245 3560);
PAINT ORANGE (-6245 3560);
FORCEPROP 1 LAST VALUE 4.75K
J 0
(-6205 3725);
DISPLAY 0.617021 (-6205 3725);
PAINT SKYBLUE (-6205 3725);
FORCEPROP 1 LAST TOLERANCE 1%
J 0
(-6205 3675);
DISPLAY 0.617021 (-6205 3675);
PAINT SKYBLUE (-6205 3675);
FORCEPROP 1 LAST WATTAGE 1/16W
J 0
(-6210 3625);
DISPLAY 0.617021 (-6210 3625);
PAINT SKYBLUE (-6210 3625);
FORCEPROP 1 LAST PACK_TYPE 0402
J 0
(-6210 3475);
DISPLAY 0.617021 (-6210 3475);
PAINT SKYBLUE (-6210 3475);
FORCEPROP 1 LASTPIN (-6250 3750) $PN 1
J 0
(-6245 3712);
DISPLAY 0.787234 (-6245 3712);
PAINT ORANGE (-6245 3712);
FORCEPROP 1 LAST LOCATION R6W8
J 0
(-6205 3775);
DISPLAY 0.617021 (-6205 3775);
PAINT AQUA (-6205 3775);
FORCEPROP 1 LAST PART_NUMBER G21796-072
J 0
(-6260 3525);
DISPLAY 0.617021 (-6260 3525);
PAINT BLUE (-6260 3525);
FORCEPROP 0 LAST CDS_LOCATION R6W8
J 0
(-6200 3825);
DISPLAY INVISIBLE (-6200 3825);
FORCEPROP 1 LAST PATH I163
J 0
(-6200 3825);
DISPLAY 0.978723 (-6200 3825);
PAINT WHITE (-6200 3825);
DISPLAY INVISIBLE (-6200 3825);
FORCEPROP 2 LAST SEC_TYPE 0402
J 0
(-6200 3875);
DISPLAY 1.021277 (-6200 3875);
PAINT ORANGE (-6200 3875);
DISPLAY INVISIBLE (-6200 3875);
FORCEPROP 0 LAST SEC 1
J 0
(-6200 3825);
DISPLAY 0.680851 (-6200 3825);
PAINT MONO (-6200 3825);
DISPLAY INVISIBLE (-6200 3825);
FORCEPROP 0 LAST ROOM HOT_SWAP
J 0
(-6200 3875);
DISPLAY 1.021277 (-6200 3875);
PAINT ORANGE (-6200 3875);
DISPLAY INVISIBLE (-6200 3875);
FORCEPROP 0 LAST NO_XNET_CONNECTION 1
J 0
(-6200 3875);
PAINT MONO (-6200 3875);
DISPLAY INVISIBLE (-6200 3875);
FORCEPROP 2 LAST CDS_LIB mstr_discrete
J 0
(-6250 3650);
PAINT MONO (-6250 3650);
DISPLAY INVISIBLE (-6250 3650);
FORCEPROP 0 LAST CDS_SEC 1
J 0
(-6200 3825);
DISPLAY INVISIBLE (-6200 3825);
FORCEADD RES..2
(-6600 3650);
FORCEPROP 1 LAST WATTAGE 1/16W
J 0
(-6560 3625);
DISPLAY 0.617021 (-6560 3625);
PAINT SKYBLUE (-6560 3625);
FORCEPROP 1 LAST TOLERANCE 1%
J 0
(-6555 3675);
DISPLAY 0.617021 (-6555 3675);
PAINT SKYBLUE (-6555 3675);
FORCEPROP 1 LASTPIN (-6600 3750) $PN 1
J 0
(-6595 3712);
DISPLAY 0.787234 (-6595 3712);
PAINT ORANGE (-6595 3712);
FORCEPROP 1 LAST LOCATION R6W7
J 0
(-6555 3775);
DISPLAY 0.617021 (-6555 3775);
PAINT AQUA (-6555 3775);
FORCEPROP 1 LAST VALUE 4.75K
J 0
(-6555 3725);
DISPLAY 0.617021 (-6555 3725);
PAINT SKYBLUE (-6555 3725);
FORCEPROP 1 LAST PACK_TYPE 0402
J 0
(-6560 3475);
DISPLAY 0.617021 (-6560 3475);
PAINT SKYBLUE (-6560 3475);
FORCEPROP 1 LASTPIN (-6600 3550) $PN 2
J 0
(-6595 3560);
DISPLAY 0.787234 (-6595 3560);
PAINT ORANGE (-6595 3560);
FORCEPROP 1 LAST MATERIAL EMPTY
J 0
(-6560 3575);
DISPLAY 0.617021 (-6560 3575);
PAINT RED (-6560 3575);
FORCEPROP 1 LAST PART_NUMBER G21796-072
J 0
(-6560 3525);
DISPLAY 0.617021 (-6560 3525);
PAINT BLUE (-6560 3525);
FORCEPROP 0 LAST CDS_LOCATION R6W7
J 0
(-6550 3825);
DISPLAY INVISIBLE (-6550 3825);
FORCEPROP 1 LAST PATH I164
J 0
(-6550 3825);
DISPLAY 0.978723 (-6550 3825);
PAINT WHITE (-6550 3825);
DISPLAY INVISIBLE (-6550 3825);
FORCEPROP 2 LAST SEC_TYPE 0402
J 0
(-6550 3875);
DISPLAY 1.021277 (-6550 3875);
PAINT ORANGE (-6550 3875);
DISPLAY INVISIBLE (-6550 3875);
FORCEPROP 2 LAST SEC 1
J 0
(-6550 3875);
DISPLAY 0.680851 (-6550 3875);
PAINT MONO (-6550 3875);
DISPLAY INVISIBLE (-6550 3875);
FORCEPROP 2 LAST CDS_LIB mstr_discrete
J 0
(-6600 3650);
PAINT MONO (-6600 3650);
DISPLAY INVISIBLE (-6600 3650);
FORCEPROP 0 LAST ROOM HOT_SWAP
J 0
(-6550 3875);
DISPLAY 1.021277 (-6550 3875);
PAINT ORANGE (-6550 3875);
DISPLAY INVISIBLE (-6550 3875);
FORCEPROP 0 LAST NO_XNET_CONNECTION 1
J 0
(-6550 3875);
PAINT MONO (-6550 3875);
DISPLAY INVISIBLE (-6550 3875);
FORCEPROP 0 LAST CDS_SEC 1
J 0
(-6550 3825);
DISPLAY INVISIBLE (-6550 3825);
FORCEADD RES..2
R 2
(-1750 3750);
FORCEPROP 1 LAST VALUE 100.0K
J 0
(-1695 3825);
DISPLAY 0.617021 (-1695 3825);
PAINT SKYBLUE (-1695 3825);
FORCEPROP 1 LAST TOLERANCE 1%
J 0
(-1695 3775);
DISPLAY 0.617021 (-1695 3775);
PAINT SKYBLUE (-1695 3775);
FORCEPROP 1 LAST WATTAGE 1/16W
J 0
(-1690 3725);
DISPLAY 0.617021 (-1690 3725);
PAINT SKYBLUE (-1690 3725);
FORCEPROP 1 LASTPIN (-1750 3650) $PN 2
J 2
(-1705 3660);
DISPLAY 0.787234 (-1705 3660);
PAINT ORANGE (-1705 3660);
FORCEPROP 1 LASTPIN (-1750 3850) $PN 1
J 2
(-1705 3812);
DISPLAY 0.787234 (-1705 3812);
PAINT ORANGE (-1705 3812);
FORCEPROP 1 LAST MATERIAL CHIP
J 0
(-1690 3675);
DISPLAY 0.617021 (-1690 3675);
PAINT SKYBLUE (-1690 3675);
FORCEPROP 1 LAST LOCATION R6W35
J 0
(-1695 3875);
DISPLAY 0.617021 (-1695 3875);
PAINT AQUA (-1695 3875);
FORCEPROP 1 LAST PACK_TYPE 0402
J 0
(-1690 3575);
DISPLAY 0.617021 (-1690 3575);
PAINT SKYBLUE (-1690 3575);
FORCEPROP 1 LAST PART_NUMBER G21796-010
J 0
(-1690 3625);
DISPLAY 0.617021 (-1690 3625);
PAINT BLUE (-1690 3625);
FORCEPROP 2 LAST ROOM HOT_SWAP
J 0
(-1800 3925);
PAINT MONO (-1800 3925);
DISPLAY INVISIBLE (-1800 3925);
FORCEPROP 1 LAST PATH I165
J 0
(-1800 3925);
DISPLAY 0.978723 (-1800 3925);
PAINT WHITE (-1800 3925);
DISPLAY INVISIBLE (-1800 3925);
FORCEPROP 2 LAST SEC 1
J 0
(-1800 3975);
PAINT MONO (-1800 3975);
DISPLAY INVISIBLE (-1800 3975);
FORCEPROP 2 LAST SEC_TYPE 0402
J 0
(-1800 3975);
DISPLAY 1.021277 (-1800 3975);
PAINT ORANGE (-1800 3975);
DISPLAY INVISIBLE (-1800 3975);
FORCEPROP 2 LAST CDS_LIB mstr_discrete
J 2
(-1750 3750);
PAINT ORANGE (-1750 3750);
DISPLAY INVISIBLE (-1750 3750);
FORCEADD GND..1
(-6600 3450);
FORCEPROP 3 LASTPIN (-6600 3500) SIG_NAME GND\g
J 0
(-6590 3510);
DISPLAY 0.659574 (-6590 3510);
PAINT MONO (-6590 3510);
DISPLAY INVISIBLE (-6590 3510);
FORCEPROP 1 LAST HDL_POWER GND
J 0
(-6600 3600);
DISPLAY 0.872340 (-6600 3600);
PAINT GREEN (-6600 3600);
DISPLAY INVISIBLE (-6600 3600);
FORCEPROP 1 LAST BODY_TYPE PLUMBING
J 0
(-6645 3407);
DISPLAY 0.340426 (-6645 3407);
PAINT GREEN (-6645 3407);
DISPLAY INVISIBLE (-6645 3407);
FORCEPROP 1 LAST SIZE 1B
J 0
(-6525 3400);
DISPLAY 0.872340 (-6525 3400);
PAINT AQUA (-6525 3400);
DISPLAY INVISIBLE (-6525 3400);
FORCEPROP 2 LAST CDS_LIB mstr_symbols
J 0
(-6600 3450);
PAINT MONO (-6600 3450);
DISPLAY INVISIBLE (-6600 3450);
FORCEPROP 1 LAST VOLTAGE 0.0V
J 0
(-6645 3407);
DISPLAY 0.340426 (-6645 3407);
PAINT GREEN (-6645 3407);
DISPLAY INVISIBLE (-6645 3407);
FORCEPROP 1 LAST PATH I4
J 0
(-6525 3450);
DISPLAY 0.872340 (-6525 3450);
PAINT AQUA (-6525 3450);
DISPLAY INVISIBLE (-6525 3450);
FORCEADD P3V3_STBY..1
(-6600 4500);
FORCEPROP 3 LASTPIN (-6600 4450) SIG_NAME P3V3_STBY\g
J 0
(-6590 4460);
DISPLAY 0.659574 (-6590 4460);
PAINT MONO (-6590 4460);
DISPLAY INVISIBLE (-6590 4460);
FORCEPROP 1 LAST HDL_POWER P3V3_STBY
J 0
(-6900 4375);
DISPLAY 0.872340 (-6900 4375);
PAINT ORANGE (-6900 4375);
DISPLAY INVISIBLE (-6900 4375);
FORCEPROP 1 LAST BODY_TYPE PLUMBING
J 0
(-6645 4457);
DISPLAY 0.340426 (-6645 4457);
PAINT GREEN (-6645 4457);
DISPLAY INVISIBLE (-6645 4457);
FORCEPROP 1 LAST SIZE 1B
J 0
(-6555 4522);
DISPLAY 0.340426 (-6555 4522);
PAINT GREEN (-6555 4522);
DISPLAY INVISIBLE (-6555 4522);
FORCEPROP 2 LAST CDS_LIB mstr_symbols
J 0
(-6600 4500);
PAINT MONO (-6600 4500);
DISPLAY INVISIBLE (-6600 4500);
FORCEPROP 1 LAST VOLTAGE 3.3V
J 0
(-6645 4457);
DISPLAY 0.340426 (-6645 4457);
PAINT GREEN (-6645 4457);
DISPLAY INVISIBLE (-6645 4457);
FORCEPROP 1 LAST PATH I6
J 0
(-6555 4502);
DISPLAY 0.340426 (-6555 4502);
PAINT GREEN (-6555 4502);
DISPLAY INVISIBLE (-6555 4502);
FORCEADD GND..1
(-6250 3450);
FORCEPROP 3 LASTPIN (-6250 3500) SIG_NAME GND\g
J 0
(-6240 3510);
DISPLAY 0.659574 (-6240 3510);
PAINT MONO (-6240 3510);
DISPLAY INVISIBLE (-6240 3510);
FORCEPROP 1 LAST HDL_POWER GND
J 0
(-6250 3600);
DISPLAY 0.872340 (-6250 3600);
PAINT GREEN (-6250 3600);
DISPLAY INVISIBLE (-6250 3600);
FORCEPROP 1 LAST BODY_TYPE PLUMBING
J 0
(-6295 3407);
DISPLAY 0.340426 (-6295 3407);
PAINT GREEN (-6295 3407);
DISPLAY INVISIBLE (-6295 3407);
FORCEPROP 1 LAST PATH I7
J 0
(-6175 3450);
DISPLAY 0.872340 (-6175 3450);
PAINT AQUA (-6175 3450);
DISPLAY INVISIBLE (-6175 3450);
FORCEPROP 1 LAST VOLTAGE 0.0V
J 0
(-6295 3407);
DISPLAY 0.340426 (-6295 3407);
PAINT GREEN (-6295 3407);
DISPLAY INVISIBLE (-6295 3407);
FORCEPROP 2 LAST CDS_LIB mstr_symbols
J 0
(-6250 3450);
PAINT MONO (-6250 3450);
DISPLAY INVISIBLE (-6250 3450);
FORCEPROP 1 LAST SIZE 1B
J 0
(-6175 3400);
DISPLAY 0.872340 (-6175 3400);
PAINT AQUA (-6175 3400);
DISPLAY INVISIBLE (-6175 3400);
FORCEADD OFFPAGE..2
(-5050 950);
FORCEPROP 2 LAST $XR3 199 
J 0
(-4861 914);
DISPLAY 0.638298 (-4861 914);
PAINT MONO (-4861 914);
FORCEPROP 2 LAST $XR2 181 
J 0
(-4621 950);
DISPLAY 0.638298 (-4621 950);
PAINT MONO (-4621 950);
FORCEPROP 2 LAST $XR1 159 
J 0
(-4741 950);
DISPLAY 0.638298 (-4741 950);
PAINT MONO (-4741 950);
FORCEPROP 2 LAST $XR0 138 
J 0
(-4861 950);
DISPLAY 0.638298 (-4861 950);
PAINT MONO (-4861 950);
FORCEPROP 1 LAST COMMENT_BODY TRUE
J 0
(-5095 855);
DISPLAY 0.872340 (-5095 855);
PAINT GREEN (-5095 855);
DISPLAY INVISIBLE (-5095 855);
FORCEPROP 1 LAST OFFPAGE TRUE
J 0
(-4725 825);
DISPLAY 0.872340 (-4725 825);
PAINT GREEN (-4725 825);
DISPLAY INVISIBLE (-4725 825);
FORCEPROP 2 LAST CDS_LIB mstr_standard
J 0
(-5050 950);
PAINT ORANGE (-5050 950);
DISPLAY INVISIBLE (-5050 950);
FORCEPROP 2 LAST PATH I74
J 0
(-4600 1000);
DISPLAY 1.021277 (-4600 1000);
PAINT ORANGE (-4600 1000);
DISPLAY INVISIBLE (-4600 1000);
FORCEADD OFFPAGE..4
R 6
(-5050 850);
FORCEPROP 2 LAST $XR1 247 
J 0
(-4714 850);
DISPLAY 0.638298 (-4714 850);
PAINT MONO (-4714 850);
FORCEPROP 2 LAST $XR0 146 
J 0
(-4834 850);
DISPLAY 0.638298 (-4834 850);
PAINT MONO (-4834 850);
FORCEPROP 1 LAST COMMENT_BODY TRUE
J 0
(-5075 909);
DISPLAY 0.872340 (-5075 909);
PAINT GREEN (-5075 909);
DISPLAY INVISIBLE (-5075 909);
FORCEPROP 1 LAST OFFPAGE TRUE
J 0
(-4725 934);
DISPLAY 0.872340 (-4725 934);
PAINT GREEN (-4725 934);
DISPLAY INVISIBLE (-4725 934);
FORCEPROP 2 LAST CDS_LIB mstr_standard
J 0
(-5050 803);
PAINT MONO (-5050 803);
DISPLAY INVISIBLE (-5050 803);
FORCEPROP 2 LAST PATH I75
J 0
(-4875 727);
DISPLAY 1.021277 (-4875 727);
PAINT ORANGE (-4875 727);
DISPLAY INVISIBLE (-4875 727);
FORCEADD OFFPAGE..1
(-7575 950);
FORCEPROP 2 LAST $XR1 247 
J 0
(-7827 986);
DISPLAY 0.638298 (-7827 986);
PAINT MONO (-7827 986);
FORCEPROP 2 LAST $XR0 119 
J 0
(-7827 950);
DISPLAY 0.638298 (-7827 950);
PAINT MONO (-7827 950);
FORCEPROP 1 LAST COMMENT_BODY TRUE
J 0
(-7450 850);
DISPLAY 0.872340 (-7450 850);
PAINT GREEN (-7450 850);
DISPLAY INVISIBLE (-7450 850);
FORCEPROP 1 LAST OFFPAGE TRUE
J 0
(-7250 825);
DISPLAY 0.872340 (-7250 825);
PAINT GREEN (-7250 825);
DISPLAY INVISIBLE (-7250 825);
FORCEPROP 2 LAST CDS_LIB mstr_standard
J 0
(-7575 950);
PAINT ORANGE (-7575 950);
DISPLAY INVISIBLE (-7575 950);
FORCEPROP 2 LAST PATH I79
J 0
(-7825 1000);
DISPLAY 1.021277 (-7825 1000);
PAINT ORANGE (-7825 1000);
DISPLAY INVISIBLE (-7825 1000);
FORCEADD OFFPAGE..6
(-7575 900);
FORCEPROP 2 LAST $XR1 247 
J 0
(-7885 864);
DISPLAY 0.638298 (-7885 864);
PAINT MONO (-7885 864);
FORCEPROP 2 LAST $XR0 119 
J 0
(-7885 900);
DISPLAY 0.638298 (-7885 900);
PAINT MONO (-7885 900);
FORCEPROP 1 LAST COMMENT_BODY TRUE
J 0
(-7475 825);
DISPLAY 0.872340 (-7475 825);
PAINT GREEN (-7475 825);
DISPLAY INVISIBLE (-7475 825);
FORCEPROP 1 LAST OFFPAGE TRUE
J 0
(-7250 775);
DISPLAY 0.872340 (-7250 775);
PAINT GREEN (-7250 775);
DISPLAY INVISIBLE (-7250 775);
FORCEPROP 2 LAST PATH I80
J 0
(-7875 950);
DISPLAY 1.021277 (-7875 950);
PAINT ORANGE (-7875 950);
DISPLAY INVISIBLE (-7875 950);
FORCEPROP 2 LAST CDS_LIB mstr_standard
J 0
(-7575 900);
PAINT ORANGE (-7575 900);
DISPLAY INVISIBLE (-7575 900);
FORCEADD P3V3_STBY..1
(-1775 2550);
FORCEPROP 3 LASTPIN (-1775 2500) SIG_NAME P3V3_STBY\g
J 0
(-1765 2510);
DISPLAY 0.659574 (-1765 2510);
PAINT MONO (-1765 2510);
DISPLAY INVISIBLE (-1765 2510);
FORCEPROP 1 LAST HDL_POWER P3V3_STBY
J 0
(-2075 2425);
DISPLAY 0.872340 (-2075 2425);
PAINT ORANGE (-2075 2425);
DISPLAY INVISIBLE (-2075 2425);
FORCEPROP 1 LAST BODY_TYPE PLUMBING
J 0
(-1820 2507);
DISPLAY 0.340426 (-1820 2507);
PAINT GREEN (-1820 2507);
DISPLAY INVISIBLE (-1820 2507);
FORCEPROP 1 LAST SIZE 1B
J 0
(-1730 2572);
DISPLAY 0.340426 (-1730 2572);
PAINT GREEN (-1730 2572);
DISPLAY INVISIBLE (-1730 2572);
FORCEPROP 2 LAST CDS_LIB mstr_symbols
J 0
(-1775 2550);
PAINT ORANGE (-1775 2550);
DISPLAY INVISIBLE (-1775 2550);
FORCEPROP 1 LAST VOLTAGE 3.3V
J 0
(-1820 2507);
DISPLAY 0.340426 (-1820 2507);
PAINT SKYBLUE (-1820 2507);
DISPLAY INVISIBLE (-1820 2507);
FORCEPROP 1 LAST PATH I83
J 0
(-1730 2552);
DISPLAY 0.340426 (-1730 2552);
PAINT GREEN (-1730 2552);
DISPLAY INVISIBLE (-1730 2552);
FORCEADD OFFPAGE..3
(-275 1750);
FORCEPROP 1 LAST COMMENT_BODY TRUE
J 0
(-325 1650);
DISPLAY 0.872340 (-325 1650);
PAINT GREEN (-325 1650);
DISPLAY INVISIBLE (-325 1650);
FORCEPROP 1 LAST OFFPAGE TRUE
J 0
(50 1625);
DISPLAY 0.872340 (50 1625);
PAINT GREEN (50 1625);
DISPLAY INVISIBLE (50 1625);
FORCEPROP 2 LAST CDS_LIB mstr_standard
J 0
(-275 1750);
PAINT ORANGE (-275 1750);
DISPLAY INVISIBLE (-275 1750);
FORCEPROP 2 LAST PATH I84
J 0
(75 1800);
DISPLAY 1.021277 (75 1800);
PAINT ORANGE (75 1800);
DISPLAY INVISIBLE (75 1800);
FORCEPROP 2 LAST $XR5 159 
J 0
(-61 1750);
DISPLAY 0.638298 (-61 1750);
PAINT MONO (-61 1750);
DISPLAY INVISIBLE (-61 1750);
FORCEPROP 2 LAST $XR4 156 
J 0
(-61 1750);
DISPLAY 0.638298 (-61 1750);
PAINT MONO (-61 1750);
DISPLAY INVISIBLE (-61 1750);
FORCEPROP 2 LAST $XR3 138 
J 0
(-61 1750);
DISPLAY 0.638298 (-61 1750);
PAINT MONO (-61 1750);
DISPLAY INVISIBLE (-61 1750);
FORCEPROP 2 LAST $XR2 111 
J 0
(-61 1750);
DISPLAY 0.638298 (-61 1750);
PAINT MONO (-61 1750);
DISPLAY INVISIBLE (-61 1750);
FORCEPROP 2 LAST $XR1 102 
J 0
(-61 1750);
DISPLAY 0.638298 (-61 1750);
PAINT MONO (-61 1750);
DISPLAY INVISIBLE (-61 1750);
FORCEPROP 2 LAST $XR0 101 
J 0
(-61 1750);
DISPLAY 0.638298 (-61 1750);
PAINT MONO (-61 1750);
DISPLAY INVISIBLE (-61 1750);
FORCEADD CAP_A..1
(-1775 2300);
FORCEPROP 1 LAST VALUE 0.1UF
J 0
(-1725 2350);
DISPLAY 0.617021 (-1725 2350);
PAINT SKYBLUE (-1725 2350);
FORCEPROP 1 LAST PART_NUMBER A36096-030
J 0
(-1725 2150);
DISPLAY 0.617021 (-1725 2150);
PAINT BLUE (-1725 2150);
FORCEPROP 1 LAST LOCATION C6W3
J 0
(-1725 2400);
DISPLAY 0.617021 (-1725 2400);
PAINT AQUA (-1725 2400);
FORCEPROP 1 LAST PACK_TYPE 0402V
J 0
(-1725 2100);
DISPLAY 0.617021 (-1725 2100);
PAINT SKYBLUE (-1725 2100);
FORCEPROP 1 LAST MATERIAL X7R
J 0
(-1725 2200);
DISPLAY 0.617021 (-1725 2200);
PAINT SKYBLUE (-1725 2200);
FORCEPROP 1 LASTPIN (-1775 2200) $PN 2
J 0
(-1765 2180);
DISPLAY 0.617021 (-1765 2180);
PAINT ORANGE (-1765 2180);
FORCEPROP 1 LAST VOLTAGE 16V
J 0
(-1725 2300);
DISPLAY 0.617021 (-1725 2300);
PAINT SKYBLUE (-1725 2300);
FORCEPROP 1 LASTPIN (-1775 2400) $PN 1
J 0
(-1765 2380);
DISPLAY 0.617021 (-1765 2380);
PAINT ORANGE (-1765 2380);
FORCEPROP 1 LAST TOLERANCE 10%
J 0
(-1725 2250);
DISPLAY 0.617021 (-1725 2250);
PAINT SKYBLUE (-1725 2250);
FORCEPROP 2 LAST BOM_COST SM_THERM
J 0
(-1725 2500);
DISPLAY 1.021277 (-1725 2500);
PAINT ORANGE (-1725 2500);
DISPLAY INVISIBLE (-1725 2500);
FORCEPROP 2 LAST SEC_TYPE 0402V
J 0
(-1725 2500);
DISPLAY 1.021277 (-1725 2500);
PAINT ORANGE (-1725 2500);
DISPLAY INVISIBLE (-1725 2500);
FORCEPROP 2 LAST SEC 1
J 0
(-1725 2500);
PAINT MONO (-1725 2500);
DISPLAY INVISIBLE (-1725 2500);
FORCEPROP 2 LAST ROOM TEMP_SENSORS
J 0
(-1725 2450);
DISPLAY 1.021277 (-1725 2450);
PAINT ORANGE (-1725 2450);
DISPLAY INVISIBLE (-1725 2450);
FORCEPROP 2 LAST CDS_SEC 1
J 0
(-1725 2450);
PAINT ORANGE (-1725 2450);
DISPLAY INVISIBLE (-1725 2450);
FORCEPROP 2 LAST CDS_LIB dev_discrete
J 0
(-1775 2300);
PAINT ORANGE (-1775 2300);
DISPLAY INVISIBLE (-1775 2300);
FORCEPROP 1 LAST PATH I85
J 0
(-1725 2450);
DISPLAY 0.978723 (-1725 2450);
PAINT WHITE (-1725 2450);
DISPLAY INVISIBLE (-1725 2450);
FORCEPROP 2 LAST CDS_LOCATION C6W3
J 0
(-1725 2400);
DISPLAY 0.617021 (-1725 2400);
PAINT AQUA (-1725 2400);
DISPLAY INVISIBLE (-1725 2400);
FORCEADD GND..1
(-1775 2050);
FORCEPROP 3 LASTPIN (-1775 2100) SIG_NAME GND\g
J 0
(-1765 2110);
DISPLAY 0.659574 (-1765 2110);
PAINT MONO (-1765 2110);
DISPLAY INVISIBLE (-1765 2110);
FORCEPROP 1 LAST HDL_POWER GND
J 0
(-1775 2200);
DISPLAY 0.872340 (-1775 2200);
PAINT GREEN (-1775 2200);
DISPLAY INVISIBLE (-1775 2200);
FORCEPROP 1 LAST BODY_TYPE PLUMBING
J 0
(-1820 2007);
DISPLAY 0.340426 (-1820 2007);
PAINT GREEN (-1820 2007);
DISPLAY INVISIBLE (-1820 2007);
FORCEPROP 1 LAST PATH I86
J 0
(-1700 2050);
DISPLAY 0.872340 (-1700 2050);
PAINT AQUA (-1700 2050);
DISPLAY INVISIBLE (-1700 2050);
FORCEPROP 1 LAST SIZE 1B
J 0
(-1700 2000);
DISPLAY 0.872340 (-1700 2000);
PAINT AQUA (-1700 2000);
DISPLAY INVISIBLE (-1700 2000);
FORCEPROP 1 LAST VOLTAGE 0.0V
J 0
(-1820 2007);
DISPLAY 0.340426 (-1820 2007);
PAINT SKYBLUE (-1820 2007);
DISPLAY INVISIBLE (-1820 2007);
FORCEPROP 2 LAST CDS_LIB mstr_symbols
J 0
(-1775 2050);
PAINT ORANGE (-1775 2050);
DISPLAY INVISIBLE (-1775 2050);
FORCEADD RES..1
(-1025 1750);
FORCEPROP 1 LAST PACK_TYPE 0402
J 0
(-900 1600);
DISPLAY 0.617021 (-900 1600);
PAINT SKYBLUE (-900 1600);
FORCEPROP 1 LAST VALUE 20.0
J 2
(-1050 1650);
DISPLAY 0.617021 (-1050 1650);
PAINT SKYBLUE (-1050 1650);
FORCEPROP 1 LAST TOLERANCE 1%
J 0
(-1025 1650);
DISPLAY 0.617021 (-1025 1650);
PAINT SKYBLUE (-1025 1650);
FORCEPROP 1 LAST LOCATION R6W20
J 0
(-1075 1800);
DISPLAY 0.617021 (-1075 1800);
PAINT AQUA (-1075 1800);
FORCEPROP 1 LAST MATERIAL CHIP
J 0
(-1025 1600);
DISPLAY 0.617021 (-1025 1600);
PAINT SKYBLUE (-1025 1600);
FORCEPROP 1 LASTPIN (-1125 1750) $PN 1
J 0
(-1113 1762);
DISPLAY 0.787234 (-1113 1762);
PAINT ORANGE (-1113 1762);
FORCEPROP 1 LASTPIN (-925 1750) $PN 2
J 0
(-963 1762);
DISPLAY 0.787234 (-963 1762);
PAINT ORANGE (-963 1762);
FORCEPROP 1 LAST WATTAGE 1/16W
J 2
(-1050 1600);
DISPLAY 0.617021 (-1050 1600);
PAINT SKYBLUE (-1050 1600);
FORCEPROP 1 LAST PART_NUMBER G21796-173
J 0
(-1075 1850);
DISPLAY 0.617021 (-1075 1850);
PAINT BLUE (-1075 1850);
FORCEPROP 2 LAST CDS_LIB mstr_discrete
J 0
(-1025 1750);
PAINT ORANGE (-1025 1750);
DISPLAY INVISIBLE (-1025 1750);
FORCEPROP 0 LAST BOM_COST SM_THERM
J 0
(-1075 2050);
DISPLAY 1.021277 (-1075 2050);
PAINT ORANGE (-1075 2050);
DISPLAY INVISIBLE (-1075 2050);
FORCEPROP 0 LAST ROOM TEMP_SENSORS
J 0
(-1075 1950);
DISPLAY 1.021277 (-1075 1950);
PAINT ORANGE (-1075 1950);
DISPLAY INVISIBLE (-1075 1950);
FORCEPROP 1 LAST PATH I87
J 0
(-1075 1900);
DISPLAY 0.978723 (-1075 1900);
PAINT WHITE (-1075 1900);
DISPLAY INVISIBLE (-1075 1900);
FORCEPROP 2 LAST CDS_LOCATION R6W20
J 0
(-1075 1800);
DISPLAY 0.617021 (-1075 1800);
PAINT AQUA (-1075 1800);
DISPLAY INVISIBLE (-1075 1800);
FORCEPROP 2 LAST SEC_TYPE 0402
J 0
(-1075 1950);
DISPLAY 1.021277 (-1075 1950);
PAINT ORANGE (-1075 1950);
DISPLAY INVISIBLE (-1075 1950);
FORCEPROP 2 LAST SEC 1
J 0
(-1075 1950);
PAINT MONO (-1075 1950);
DISPLAY INVISIBLE (-1075 1950);
FORCEADD P3V3_STBY..1
(-3200 2500);
FORCEPROP 3 LASTPIN (-3200 2450) SIG_NAME P3V3_STBY\g
J 0
(-3190 2460);
DISPLAY 0.659574 (-3190 2460);
PAINT MONO (-3190 2460);
DISPLAY INVISIBLE (-3190 2460);
FORCEPROP 1 LAST SIZE 1B
J 0
(-3155 2522);
DISPLAY 0.340426 (-3155 2522);
PAINT GREEN (-3155 2522);
DISPLAY INVISIBLE (-3155 2522);
FORCEPROP 1 LAST VOLTAGE 3.3V
J 0
(-3245 2457);
DISPLAY 0.340426 (-3245 2457);
PAINT SKYBLUE (-3245 2457);
DISPLAY INVISIBLE (-3245 2457);
FORCEPROP 2 LAST CDS_LIB mstr_symbols
J 0
(-3200 2500);
PAINT MONO (-3200 2500);
DISPLAY INVISIBLE (-3200 2500);
FORCEPROP 1 LAST PATH I88
J 0
(-3155 2502);
DISPLAY 0.340426 (-3155 2502);
PAINT GREEN (-3155 2502);
DISPLAY INVISIBLE (-3155 2502);
FORCEPROP 1 LAST BODY_TYPE PLUMBING
J 0
(-3245 2457);
DISPLAY 0.340426 (-3245 2457);
PAINT GREEN (-3245 2457);
DISPLAY INVISIBLE (-3245 2457);
FORCEPROP 1 LAST HDL_POWER P3V3_STBY
J 0
(-3500 2375);
DISPLAY 0.872340 (-3500 2375);
PAINT ORANGE (-3500 2375);
DISPLAY INVISIBLE (-3500 2375);
FORCEADD AT24C64..1
(-2200 1850);
FORCEPROP 1 LAST LOCATION U6W3
J 0
(-2450 2200);
DISPLAY 0.617021 (-2450 2200);
PAINT AQUA (-2450 2200);
FORCEPROP 2 LASTPIN (-2500 1950) $PN 3
J 2
(-2510 1960);
DISPLAY 0.617021 (-2510 1960);
PAINT ORANGE (-2510 1960);
FORCEPROP 2 LASTPIN (-2500 1900) $PN 2
J 2
(-2510 1910);
DISPLAY 0.617021 (-2510 1910);
PAINT ORANGE (-2510 1910);
FORCEPROP 2 LASTPIN (-2500 1850) $PN 1
J 2
(-2510 1860);
DISPLAY 0.617021 (-2510 1860);
PAINT ORANGE (-2510 1860);
FORCEPROP 2 LASTPIN (-1900 1750) $PN 5
J 0
(-1890 1760);
DISPLAY 0.617021 (-1890 1760);
PAINT ORANGE (-1890 1760);
FORCEPROP 2 LASTPIN (-2500 1750) $PN 6
J 2
(-2510 1760);
DISPLAY 0.617021 (-2510 1760);
PAINT ORANGE (-2510 1760);
FORCEPROP 2 LASTPIN (-2500 1700) $PN 7
J 2
(-2510 1710);
DISPLAY 0.617021 (-2510 1710);
PAINT ORANGE (-2510 1710);
FORCEPROP 1 LAST MATERIAL IC
J 0
(-2450 2150);
DISPLAY 0.617021 (-2450 2150);
PAINT SKYBLUE (-2450 2150);
FORCEPROP 1 LAST PART_NUMBER C47049-001
J 0
(-2450 1500);
DISPLAY 0.617021 (-2450 1500);
PAINT BLUE (-2450 1500);
FORCEPROP 1 LAST POWER_GROUP VCC=P3V3_STBY;GND=GND;
J 0
(-2450 1450);
DISPLAY 0.617021 (-2450 1450);
PAINT ORANGE (-2450 1450);
FORCEPROP 1 LAST PATH I89
J 0
(-2025 2150);
DISPLAY 0.957447 (-2025 2150);
PAINT PURPLE (-2025 2150);
DISPLAY INVISIBLE (-2025 2150);
FORCEPROP 2 LAST CDS_LIB mstr_memory
J 0
(-2200 1850);
PAINT ORANGE (-2200 1850);
DISPLAY INVISIBLE (-2200 1850);
FORCEPROP 2 LAST ROOM TEMP_SENSORS
J 0
(-2450 2250);
DISPLAY 1.021277 (-2450 2250);
PAINT ORANGE (-2450 2250);
DISPLAY INVISIBLE (-2450 2250);
FORCEPROP 1 LAST PACK_TYPE SOICLF
J 0
(-2450 2250);
DISPLAY 0.957447 (-2450 2250);
PAINT SKYBLUE (-2450 2250);
DISPLAY INVISIBLE (-2450 2250);
FORCEPROP 2 LAST SEC_TYPE SOICLF
J 0
(-2450 2250);
DISPLAY 1.021277 (-2450 2250);
PAINT ORANGE (-2450 2250);
DISPLAY INVISIBLE (-2450 2250);
FORCEPROP 2 LAST BOM_COST SM_THERM
J 0
(-2450 2300);
DISPLAY 1.021277 (-2450 2300);
PAINT ORANGE (-2450 2300);
DISPLAY INVISIBLE (-2450 2300);
FORCEPROP 2 LAST SEC 1
J 0
(-2450 2250);
DISPLAY 0.680851 (-2450 2250);
PAINT MONO (-2450 2250);
DISPLAY INVISIBLE (-2450 2250);
FORCEPROP 2 LAST CDS_LOCATION U6W3
J 0
(-2450 2200);
DISPLAY 0.617021 (-2450 2200);
PAINT AQUA (-2450 2200);
DISPLAY INVISIBLE (-2450 2200);
FORCEADD RES..2
(-3200 2200);
FORCEPROP 1 LAST PART_NUMBER G21796-026
J 0
(-3160 2125);
DISPLAY 0.617021 (-3160 2125);
PAINT BLUE (-3160 2125);
FORCEPROP 1 LAST WATTAGE 1/16W
J 0
(-3160 2225);
DISPLAY 0.617021 (-3160 2225);
PAINT SKYBLUE (-3160 2225);
FORCEPROP 1 LAST MATERIAL CHIP
J 0
(-3160 2175);
DISPLAY 0.617021 (-3160 2175);
PAINT SKYBLUE (-3160 2175);
FORCEPROP 1 LAST PACK_TYPE 0402
J 0
(-3160 2075);
DISPLAY 0.617021 (-3160 2075);
PAINT SKYBLUE (-3160 2075);
FORCEPROP 1 LAST TOLERANCE 1%
J 0
(-3155 2275);
DISPLAY 0.617021 (-3155 2275);
PAINT SKYBLUE (-3155 2275);
FORCEPROP 1 LAST VALUE 1.00K
J 0
(-3155 2325);
DISPLAY 0.617021 (-3155 2325);
PAINT SKYBLUE (-3155 2325);
FORCEPROP 1 LASTPIN (-3200 2100) $PN 2
J 0
(-3195 2110);
DISPLAY 0.617021 (-3195 2110);
PAINT ORANGE (-3195 2110);
FORCEPROP 1 LASTPIN (-3200 2300) $PN 1
J 0
(-3195 2262);
DISPLAY 0.617021 (-3195 2262);
PAINT ORANGE (-3195 2262);
FORCEPROP 1 LAST LOCATION R6W21
J 0
(-3155 2375);
DISPLAY 0.617021 (-3155 2375);
PAINT AQUA (-3155 2375);
FORCEPROP 2 LAST CDS_LOCATION R6W21
J 0
(-3155 2325);
DISPLAY 0.617021 (-3155 2325);
PAINT AQUA (-3155 2325);
DISPLAY INVISIBLE (-3155 2325);
FORCEPROP 2 LAST ROOM TEMP_SENSORS
J 0
(-3150 2375);
DISPLAY 1.021277 (-3150 2375);
PAINT ORANGE (-3150 2375);
DISPLAY INVISIBLE (-3150 2375);
FORCEPROP 0 LAST SEC 1
J 0
(-3150 2375);
DISPLAY 0.680851 (-3150 2375);
PAINT MONO (-3150 2375);
DISPLAY INVISIBLE (-3150 2375);
FORCEPROP 2 LAST BOM_COST SM_THERM
J 0
(-3150 2425);
DISPLAY 1.021277 (-3150 2425);
PAINT ORANGE (-3150 2425);
DISPLAY INVISIBLE (-3150 2425);
FORCEPROP 2 LAST SEC_TYPE 0402
J 0
(-3150 2425);
DISPLAY 1.021277 (-3150 2425);
PAINT ORANGE (-3150 2425);
DISPLAY INVISIBLE (-3150 2425);
FORCEPROP 2 LAST CDS_LIB mstr_discrete
J 0
(-3200 2200);
PAINT ORANGE (-3200 2200);
DISPLAY INVISIBLE (-3200 2200);
FORCEPROP 1 LAST PATH I90
J 0
(-3150 2375);
DISPLAY 0.978723 (-3150 2375);
PAINT WHITE (-3150 2375);
DISPLAY INVISIBLE (-3150 2375);
FORCEADD GND..1
(-2700 1925);
FORCEPROP 3 LASTPIN (-2700 1975) SIG_NAME GND\g
J 0
(-2690 1985);
DISPLAY 0.659574 (-2690 1985);
PAINT MONO (-2690 1985);
DISPLAY INVISIBLE (-2690 1985);
FORCEPROP 1 LAST HDL_POWER GND
J 0
(-2700 2075);
DISPLAY 0.872340 (-2700 2075);
PAINT GREEN (-2700 2075);
DISPLAY INVISIBLE (-2700 2075);
FORCEPROP 1 LAST BODY_TYPE PLUMBING
J 0
(-2745 1882);
DISPLAY 0.340426 (-2745 1882);
PAINT GREEN (-2745 1882);
DISPLAY INVISIBLE (-2745 1882);
FORCEPROP 1 LAST SIZE 1B
J 0
(-2625 1875);
DISPLAY 0.872340 (-2625 1875);
PAINT AQUA (-2625 1875);
DISPLAY INVISIBLE (-2625 1875);
FORCEPROP 2 LAST CDS_LIB mstr_symbols
J 0
(-2700 1925);
PAINT ORANGE (-2700 1925);
DISPLAY INVISIBLE (-2700 1925);
FORCEPROP 1 LAST VOLTAGE 0.0V
J 0
(-2745 1882);
DISPLAY 0.340426 (-2745 1882);
PAINT SKYBLUE (-2745 1882);
DISPLAY INVISIBLE (-2745 1882);
FORCEPROP 1 LAST PATH I91
J 0
(-2625 1925);
DISPLAY 0.872340 (-2625 1925);
PAINT AQUA (-2625 1925);
DISPLAY INVISIBLE (-2625 1925);
FORCEADD RES..2
(-3200 1500);
FORCEPROP 1 LAST PART_NUMBER G21796-026
J 0
(-3160 1375);
DISPLAY 0.617021 (-3160 1375);
PAINT BLUE (-3160 1375);
FORCEPROP 1 LAST WATTAGE 1/16W
J 0
(-3160 1475);
DISPLAY 0.617021 (-3160 1475);
PAINT SKYBLUE (-3160 1475);
FORCEPROP 1 LAST PACK_TYPE 0402
J 0
(-3160 1325);
DISPLAY 0.617021 (-3160 1325);
PAINT SKYBLUE (-3160 1325);
FORCEPROP 1 LAST MATERIAL CHIP
J 0
(-3160 1425);
DISPLAY 0.617021 (-3160 1425);
PAINT SKYBLUE (-3160 1425);
FORCEPROP 1 LASTPIN (-3200 1400) $PN 2
J 0
(-3195 1410);
DISPLAY 0.617021 (-3195 1410);
PAINT ORANGE (-3195 1410);
FORCEPROP 1 LAST LOCATION R6W23
J 0
(-3155 1625);
DISPLAY 0.617021 (-3155 1625);
PAINT AQUA (-3155 1625);
FORCEPROP 1 LASTPIN (-3200 1600) $PN 1
J 0
(-3195 1562);
DISPLAY 0.617021 (-3195 1562);
PAINT ORANGE (-3195 1562);
FORCEPROP 1 LAST VALUE 1.00K
J 0
(-3155 1575);
DISPLAY 0.617021 (-3155 1575);
PAINT SKYBLUE (-3155 1575);
FORCEPROP 1 LAST TOLERANCE 1%
J 0
(-3155 1525);
DISPLAY 0.617021 (-3155 1525);
PAINT SKYBLUE (-3155 1525);
FORCEPROP 1 LAST PATH I92
J 0
(-3150 1675);
DISPLAY 0.978723 (-3150 1675);
PAINT WHITE (-3150 1675);
DISPLAY INVISIBLE (-3150 1675);
FORCEPROP 2 LAST CDS_LIB mstr_discrete
J 0
(-3200 1500);
PAINT ORANGE (-3200 1500);
DISPLAY INVISIBLE (-3200 1500);
FORCEPROP 0 LAST SEC 1
J 0
(-3150 1675);
DISPLAY 0.680851 (-3150 1675);
PAINT MONO (-3150 1675);
DISPLAY INVISIBLE (-3150 1675);
FORCEPROP 2 LAST ROOM TEMP_SENSORS
J 0
(-3150 1675);
DISPLAY 1.021277 (-3150 1675);
PAINT ORANGE (-3150 1675);
DISPLAY INVISIBLE (-3150 1675);
FORCEPROP 2 LAST BOM_COST SM_THERM
J 0
(-3150 1725);
DISPLAY 1.021277 (-3150 1725);
PAINT ORANGE (-3150 1725);
DISPLAY INVISIBLE (-3150 1725);
FORCEPROP 2 LAST SEC_TYPE 0402
J 0
(-3150 1725);
DISPLAY 1.021277 (-3150 1725);
PAINT ORANGE (-3150 1725);
DISPLAY INVISIBLE (-3150 1725);
FORCEPROP 2 LAST CDS_LOCATION R6W23
J 0
(-3155 1625);
DISPLAY 0.617021 (-3155 1625);
PAINT AQUA (-3155 1625);
DISPLAY INVISIBLE (-3155 1625);
FORCEADD GND..1
(-3200 1300);
FORCEPROP 3 LASTPIN (-3200 1350) SIG_NAME GND\g
J 0
(-3190 1360);
DISPLAY 0.659574 (-3190 1360);
PAINT MONO (-3190 1360);
DISPLAY INVISIBLE (-3190 1360);
FORCEPROP 1 LAST HDL_POWER GND
J 0
(-3200 1450);
DISPLAY 0.872340 (-3200 1450);
PAINT GREEN (-3200 1450);
DISPLAY INVISIBLE (-3200 1450);
FORCEPROP 1 LAST BODY_TYPE PLUMBING
J 0
(-3245 1257);
DISPLAY 0.340426 (-3245 1257);
PAINT GREEN (-3245 1257);
DISPLAY INVISIBLE (-3245 1257);
FORCEPROP 2 LAST CDS_LIB mstr_symbols
J 0
(-3200 1300);
PAINT ORANGE (-3200 1300);
DISPLAY INVISIBLE (-3200 1300);
FORCEPROP 1 LAST SIZE 1B
J 0
(-3125 1250);
DISPLAY 0.872340 (-3125 1250);
PAINT AQUA (-3125 1250);
DISPLAY INVISIBLE (-3125 1250);
FORCEPROP 1 LAST VOLTAGE 0.0V
J 0
(-3245 1257);
DISPLAY 0.340426 (-3245 1257);
PAINT SKYBLUE (-3245 1257);
DISPLAY INVISIBLE (-3245 1257);
FORCEPROP 1 LAST PATH I93
J 0
(-3125 1300);
DISPLAY 0.872340 (-3125 1300);
PAINT AQUA (-3125 1300);
DISPLAY INVISIBLE (-3125 1300);
FORCEADD RES..1
(-3425 1750);
FORCEPROP 1 LAST PART_NUMBER G21796-173
J 0
(-3475 1850);
DISPLAY 0.617021 (-3475 1850);
PAINT BLUE (-3475 1850);
FORCEPROP 1 LAST MATERIAL CHIP
J 0
(-3425 1600);
DISPLAY 0.617021 (-3425 1600);
PAINT SKYBLUE (-3425 1600);
FORCEPROP 1 LAST TOLERANCE 1%
J 0
(-3425 1650);
DISPLAY 0.617021 (-3425 1650);
PAINT SKYBLUE (-3425 1650);
FORCEPROP 1 LAST VALUE 20.0
J 2
(-3450 1650);
DISPLAY 0.617021 (-3450 1650);
PAINT SKYBLUE (-3450 1650);
FORCEPROP 1 LAST PACK_TYPE 0402
J 0
(-3525 1550);
DISPLAY 0.617021 (-3525 1550);
PAINT SKYBLUE (-3525 1550);
FORCEPROP 1 LASTPIN (-3525 1750) $PN 1
J 0
(-3513 1762);
DISPLAY 0.617021 (-3513 1762);
PAINT ORANGE (-3513 1762);
FORCEPROP 1 LASTPIN (-3325 1750) $PN 2
J 0
(-3363 1762);
DISPLAY 0.617021 (-3363 1762);
PAINT ORANGE (-3363 1762);
FORCEPROP 1 LAST WATTAGE 1/16W
J 2
(-3450 1600);
DISPLAY 0.617021 (-3450 1600);
PAINT SKYBLUE (-3450 1600);
FORCEPROP 1 LAST LOCATION R6W22
J 0
(-3475 1800);
DISPLAY 0.617021 (-3475 1800);
PAINT AQUA (-3475 1800);
FORCEPROP 2 LAST CDS_LOCATION R6W22
J 0
(-3475 1800);
DISPLAY 0.617021 (-3475 1800);
PAINT AQUA (-3475 1800);
DISPLAY INVISIBLE (-3475 1800);
FORCEPROP 1 LAST PATH I94
J 0
(-3475 1900);
DISPLAY 0.978723 (-3475 1900);
PAINT WHITE (-3475 1900);
DISPLAY INVISIBLE (-3475 1900);
FORCEPROP 0 LAST SEC 1
J 0
(-3475 1900);
DISPLAY 0.680851 (-3475 1900);
PAINT MONO (-3475 1900);
DISPLAY INVISIBLE (-3475 1900);
FORCEPROP 2 LAST CDS_LIB mstr_discrete
J 0
(-3425 1750);
PAINT ORANGE (-3425 1750);
DISPLAY INVISIBLE (-3425 1750);
FORCEPROP 0 LAST ROOM TEMP_SENSORS
J 0
(-3475 1950);
DISPLAY 1.021277 (-3475 1950);
PAINT ORANGE (-3475 1950);
DISPLAY INVISIBLE (-3475 1950);
FORCEPROP 2 LAST SEC_TYPE 0402
J 0
(-3475 1950);
DISPLAY 1.021277 (-3475 1950);
PAINT ORANGE (-3475 1950);
DISPLAY INVISIBLE (-3475 1950);
FORCEPROP 0 LAST BOM_COST SM_THERM
J 0
(-3475 2050);
DISPLAY 1.021277 (-3475 2050);
PAINT ORANGE (-3475 2050);
DISPLAY INVISIBLE (-3475 2050);
FORCEADD OFFPAGE..1
(-4200 1750);
FORCEPROP 2 LAST $XR5 156 
J 0
(-5202 1750);
DISPLAY 0.638298 (-5202 1750);
PAINT MONO (-5202 1750);
FORCEPROP 2 LAST $XR4 111 
J 0
(-5082 1750);
DISPLAY 0.638298 (-5082 1750);
PAINT MONO (-5082 1750);
FORCEPROP 2 LAST $XR3 102 
J 0
(-4962 1750);
DISPLAY 0.638298 (-4962 1750);
PAINT MONO (-4962 1750);
FORCEPROP 2 LAST $XR2 101 
J 0
(-4842 1750);
DISPLAY 0.638298 (-4842 1750);
PAINT MONO (-4842 1750);
FORCEPROP 2 LAST $XR1 159 
J 0
(-4722 1750);
DISPLAY 0.638298 (-4722 1750);
PAINT MONO (-4722 1750);
FORCEPROP 2 LAST $XR0 138 
J 0
(-4602 1750);
DISPLAY 0.638298 (-4602 1750);
PAINT MONO (-4602 1750);
FORCEPROP 1 LAST COMMENT_BODY TRUE
J 0
(-4075 1650);
DISPLAY 0.872340 (-4075 1650);
PAINT GREEN (-4075 1650);
DISPLAY INVISIBLE (-4075 1650);
FORCEPROP 1 LAST OFFPAGE TRUE
J 0
(-3875 1625);
DISPLAY 0.872340 (-3875 1625);
PAINT GREEN (-3875 1625);
DISPLAY INVISIBLE (-3875 1625);
FORCEPROP 2 LAST CDS_LIB mstr_standard
J 0
(-4200 1750);
PAINT ORANGE (-4200 1750);
DISPLAY INVISIBLE (-4200 1750);
FORCEPROP 2 LAST PATH I95
J 0
(-4450 1800);
DISPLAY 1.021277 (-4450 1800);
PAINT ORANGE (-4450 1800);
DISPLAY INVISIBLE (-4450 1800);
FORCEADD OFFPAGE..3
(-5050 900);
FORCEPROP 1 LAST COMMENT_BODY TRUE
J 0
(-5100 800);
DISPLAY 0.872340 (-5100 800);
PAINT GREEN (-5100 800);
DISPLAY INVISIBLE (-5100 800);
FORCEPROP 1 LAST OFFPAGE TRUE
J 0
(-4725 775);
DISPLAY 0.872340 (-4725 775);
PAINT GREEN (-4725 775);
DISPLAY INVISIBLE (-4725 775);
FORCEPROP 2 LAST PATH I96
J 0
(-4575 950);
DISPLAY 1.021277 (-4575 950);
PAINT ORANGE (-4575 950);
DISPLAY INVISIBLE (-4575 950);
FORCEPROP 2 LAST CDS_LIB mstr_standard
J 0
(-5050 900);
PAINT ORANGE (-5050 900);
DISPLAY INVISIBLE (-5050 900);
FORCEPROP 2 LAST $XR3 199 
J 0
(-4836 900);
DISPLAY 0.638298 (-4836 900);
PAINT MONO (-4836 900);
DISPLAY INVISIBLE (-4836 900);
FORCEPROP 2 LAST $XR2 181 
J 0
(-4836 900);
DISPLAY 0.638298 (-4836 900);
PAINT MONO (-4836 900);
DISPLAY INVISIBLE (-4836 900);
FORCEPROP 2 LAST $XR1 159 
J 0
(-4836 900);
DISPLAY 0.638298 (-4836 900);
PAINT MONO (-4836 900);
DISPLAY INVISIBLE (-4836 900);
FORCEPROP 2 LAST $XR0 138 
J 0
(-4836 900);
DISPLAY 0.638298 (-4836 900);
PAINT MONO (-4836 900);
DISPLAY INVISIBLE (-4836 900);
FORCEADD RES..1
R 1
(-7350 3350);
FORCEPROP 1 LAST LOCATION R6W11
J 0
(-7300 3475);
DISPLAY 0.638298 (-7300 3475);
PAINT SKYBLUE (-7300 3475);
FORCEPROP 1 LAST VALUE 4.75K
J 2
(-7200 3425);
DISPLAY 0.638298 (-7200 3425);
PAINT SKYBLUE (-7200 3425);
FORCEPROP 1 LAST WATTAGE 1/16W
J 2
(-7175 3325);
DISPLAY 0.638298 (-7175 3325);
PAINT SKYBLUE (-7175 3325);
FORCEPROP 1 LAST MATERIAL CHIP
J 0
(-7300 3275);
DISPLAY 0.638298 (-7300 3275);
PAINT SKYBLUE (-7300 3275);
FORCEPROP 1 LAST PART_NUMBER G21796-072
J 0
(-7300 3225);
DISPLAY 0.638298 (-7300 3225);
PAINT BLUE (-7300 3225);
FORCEPROP 1 LAST PACK_TYPE 0402
J 0
(-7300 3175);
DISPLAY 0.638298 (-7300 3175);
PAINT SKYBLUE (-7300 3175);
FORCEPROP 1 LASTPIN (-7350 3450) $PN 2
R 1
J 0
(-7362 3412);
DISPLAY 0.787234 (-7362 3412);
PAINT ORANGE (-7362 3412);
FORCEPROP 1 LAST TOLERANCE 1%
J 0
(-7300 3375);
DISPLAY 0.638298 (-7300 3375);
PAINT SKYBLUE (-7300 3375);
FORCEPROP 1 LASTPIN (-7350 3250) $PN 1
R 1
J 0
(-7362 3262);
DISPLAY 0.787234 (-7362 3262);
PAINT ORANGE (-7362 3262);
FORCEPROP 0 LAST SEC 1
R 1
J 0
(-7300 3525);
DISPLAY 0.680851 (-7300 3525);
PAINT MONO (-7300 3525);
DISPLAY INVISIBLE (-7300 3525);
FORCEPROP 2 LAST SEC_TYPE 0402
J 0
(-7300 3525);
DISPLAY 1.021277 (-7300 3525);
PAINT ORANGE (-7300 3525);
DISPLAY INVISIBLE (-7300 3525);
FORCEPROP 1 LAST PATH I98
R 1
J 0
(-7500 3300);
DISPLAY 0.978723 (-7500 3300);
PAINT WHITE (-7500 3300);
DISPLAY INVISIBLE (-7500 3300);
FORCEPROP 2 LAST CDS_LIB mstr_discrete
R 1
J 0
(-7350 3350);
PAINT MONO (-7350 3350);
DISPLAY INVISIBLE (-7350 3350);
FORCEADD RES..1
R 1
(-7050 3350);
FORCEPROP 1 LAST MATERIAL CHIP
J 0
(-7000 3275);
DISPLAY 0.638298 (-7000 3275);
PAINT SKYBLUE (-7000 3275);
FORCEPROP 1 LAST PART_NUMBER G21796-072
J 0
(-7000 3225);
DISPLAY 0.638298 (-7000 3225);
PAINT BLUE (-7000 3225);
FORCEPROP 1 LAST TOLERANCE 1%
J 0
(-7000 3375);
DISPLAY 0.638298 (-7000 3375);
PAINT SKYBLUE (-7000 3375);
FORCEPROP 1 LAST WATTAGE 1/16W
J 2
(-6875 3325);
DISPLAY 0.638298 (-6875 3325);
PAINT SKYBLUE (-6875 3325);
FORCEPROP 1 LASTPIN (-7050 3450) $PN 2
R 1
J 0
(-7062 3412);
DISPLAY 0.787234 (-7062 3412);
PAINT ORANGE (-7062 3412);
FORCEPROP 1 LAST PACK_TYPE 0402
J 0
(-7000 3175);
DISPLAY 0.638298 (-7000 3175);
PAINT SKYBLUE (-7000 3175);
FORCEPROP 1 LASTPIN (-7050 3250) $PN 1
R 1
J 0
(-7062 3262);
DISPLAY 0.787234 (-7062 3262);
PAINT ORANGE (-7062 3262);
FORCEPROP 1 LAST VALUE 4.75K
J 2
(-6900 3425);
DISPLAY 0.638298 (-6900 3425);
PAINT SKYBLUE (-6900 3425);
FORCEPROP 1 LAST LOCATION R6W12
J 0
(-7000 3475);
DISPLAY 0.638298 (-7000 3475);
PAINT SKYBLUE (-7000 3475);
FORCEPROP 2 LAST CDS_LIB mstr_discrete
J 0
(-7050 3350);
PAINT MONO (-7050 3350);
DISPLAY INVISIBLE (-7050 3350);
FORCEPROP 2 LAST SEC_TYPE 0402
J 0
(-7000 3525);
DISPLAY 1.021277 (-7000 3525);
PAINT ORANGE (-7000 3525);
DISPLAY INVISIBLE (-7000 3525);
FORCEPROP 0 LAST SEC 1
R 1
J 0
(-7000 3525);
DISPLAY 0.680851 (-7000 3525);
PAINT MONO (-7000 3525);
DISPLAY INVISIBLE (-7000 3525);
FORCEPROP 1 LAST PATH I99
R 1
J 0
(-7200 3300);
DISPLAY 0.978723 (-7200 3300);
PAINT WHITE (-7200 3300);
DISPLAY INVISIBLE (-7200 3300);
FORCEADD DNS..2
(-6595 3645);
PAINT RED (-6595 3645);
FORCEPROP 1 LAST COMMENT_BODY TRUE
R 1
J 0
(-6520 3420);
DISPLAY 0.872340 (-6520 3420);
PAINT GREEN (-6520 3420);
DISPLAY INVISIBLE (-6520 3420);
FORCEPROP 2 LAST CDS_LIB mstr_misc
J 0
(-6595 3645);
PAINT MONO (-6595 3645);
DISPLAY INVISIBLE (-6595 3645);
FORCEADD CAD_NOTE..1
(-3925 1250);
FORCEPROP 0 LAST L1 PLACE SERIES RESISTORS ON SMB_HOST_STBY_LVC3_SDA/SCL NETS CLOSE TO AT24C64
J 0
(-4075 1075);
DISPLAY 0.808511 (-4075 1075);
PAINT ORANGE (-4075 1075);
FORCEPROP 1 LAST COMMENT_BODY TRUE
J 0
(-3900 1350);
DISPLAY 0.978723 (-3900 1350);
PAINT ORANGE (-3900 1350);
DISPLAY INVISIBLE (-3900 1350);
FORCEPROP 2 LAST CDS_LIB mstr_symbols
J 0
(-3925 1250);
PAINT ORANGE (-3925 1250);
DISPLAY INVISIBLE (-3925 1250);
FORCEADD DESIGN_NOTE..1
(-1625 1250);
FORCEPROP 1 LAST COMMENT_BODY TRUE
J 0
(-1600 1350);
DISPLAY 0.978723 (-1600 1350);
PAINT ORANGE (-1600 1350);
DISPLAY INVISIBLE (-1600 1350);
FORCEPROP 2 LAST CDS_LIB mstr_symbols
J 0
(-1625 1250);
PAINT ORANGE (-1625 1250);
DISPLAY INVISIBLE (-1625 1250);
FORCEADD INTEL_CORP_BPAGE..1
(0 0);
FORCEPROP 1 LAST CDS_CON_LAST_MODIFIED Fri Jun 16 17:49:29 2017
J 0
(-1425 325);
PAINT ORANGE (-1425 325);
DISPLAY INVISIBLE (-1425 325);
FORCEPROP 1 LAST CUSTOM_TXT_CDS <CURRENT_DESIGN_SHEET> OF <TOTAL_DESIGN_SHEETS>
J 0
(-500 25);
PAINT ORANGE (-500 25);
FORCEPROP 1 LAST CUSTOM_TXT_CDS <CON_LAST_MODIFIED>
J 0
(-4000 100);
PAINT ORANGE (-4000 100);
FORCEPROP 2 LAST CUSTOM_TXT_CDS <XR_PAGE_TITLE>
J 0
(-7890 5250);
DISPLAY 0.638298 (-7890 5250);
PAINT PINK (-7890 5250);
DISPLAY INVISIBLE (-7890 5250);
FORCEPROP 1 LAST SCH_TITLE USB3.0 DEBUG PORT, SMBUS MASTER SWITCH & BIOS SPFT BOARD ID
J 0
(-7950 50);
DISPLAY 1.255319 (-7950 50);
PAINT ORANGE (-7950 50);
FORCEPROP 1 LAST COMMENT_BODY TRUE
J 0
(12 12);
DISPLAY 0.468085 (12 12);
PAINT GREEN (12 12);
DISPLAY INVISIBLE (12 12);
FORCEPROP 2 LAST PAGE_BORDER TRUE
J 0
(-7890 5250);
DISPLAY 0.638298 (-7890 5250);
PAINT PINK (-7890 5250);
DISPLAY INVISIBLE (-7890 5250);
FORCEPROP 2 LAST CDS_LIB mstr_symbols
J 0
(0 0);
PAINT MONO (0 0);
DISPLAY INVISIBLE (0 0);
FORCEPROP 2 LAST CDS_XR_PAGE_TITLE CR-247 : @BASEBOARD_FAB2_LIB.BASEBOARD_FAB2(SCH_1):PAGE247
J 0
(-7890 5250);
DISPLAY 0.638298 (-7890 5250);
PAINT PINK (-7890 5250);
DISPLAY INVISIBLE (-7890 5250);
FORCEADD DNS..2
(-5895 3645);
PAINT RED (-5895 3645);
FORCEPROP 1 LAST COMMENT_BODY TRUE
R 1
J 0
(-5820 3420);
DISPLAY 0.872340 (-5820 3420);
PAINT GREEN (-5820 3420);
DISPLAY INVISIBLE (-5820 3420);
FORCEPROP 2 LAST CDS_LIB mstr_misc
J 0
(-5895 3645);
PAINT MONO (-5895 3645);
DISPLAY INVISIBLE (-5895 3645);
FORCEADD DNS..2
(-6245 3645);
PAINT RED (-6245 3645);
FORCEPROP 1 LAST COMMENT_BODY TRUE
R 1
J 0
(-6170 3420);
DISPLAY 0.872340 (-6170 3420);
PAINT GREEN (-6170 3420);
DISPLAY INVISIBLE (-6170 3420);
FORCEPROP 2 LAST CDS_LIB mstr_misc
J 0
(-6245 3645);
PAINT MONO (-6245 3645);
DISPLAY INVISIBLE (-6245 3645);
FORCEADD CAD_NOTE..1
(-1400 2575);
FORCEPROP 0 LAST L1 PLACE CAP CLOSE
J 0
(-1550 2450);
DISPLAY 1.021277 (-1550 2450);
PAINT ORANGE (-1550 2450);
FORCEPROP 0 LAST L2 TO AT24C64
J 0
(-1550 2375);
DISPLAY 1.021277 (-1550 2375);
PAINT ORANGE (-1550 2375);
FORCEPROP 1 LAST COMMENT_BODY TRUE
J 0
(-1375 2675);
DISPLAY 0.978723 (-1375 2675);
PAINT ORANGE (-1375 2675);
DISPLAY INVISIBLE (-1375 2675);
FORCEPROP 2 LAST CDS_LIB mstr_symbols
J 0
(-1400 2575);
PAINT ORANGE (-1400 2575);
DISPLAY INVISIBLE (-1400 2575);
WIRE 16 -1 (-7550 2200)(-7550 2150);
WIRE 16 -1 (-7550 2150)(-7200 2150);
WIRE 16 -1 (-7550 2150)(-7550 2050);
WIRE 16 -1 (-7200 2150)(-6850 2150);
WIRE 16 -1 (-7200 2150)(-7200 2050);
WIRE 16 -1 (-6850 2150)(-6850 2050);
WIRE 16 -1 (-7250 1150)(-7250 1100);
WIRE 16 -1 (-5500 1100)(-5500 1150);
WIRE 16 -1 (-5950 1450)(-5950 1400);
WIRE 16 -1 (-5500 1400)(-5950 1400);
WIRE 16 -1 (-5950 1000)(-5950 1400);
WIRE 16 -1 (-6050 1000)(-5950 1000);
WIRE 16 -1 (-5500 1400)(-5500 1350);
WIRE 16 -1 (-6900 1450)(-6900 1400);
WIRE 16 -1 (-6900 1000)(-6900 1400);
WIRE 16 -1 (-6900 1400)(-7250 1400);
WIRE 16 -1 (-7250 1400)(-7250 1350);
WIRE 16 -1 (-6700 1000)(-6900 1000);
WIRE 16 -1 (-6750 850)(-6750 800);
WIRE 16 -1 (-6700 850)(-6750 850);
WIRE 16 -1 (-7450 3650)(-7450 3600);
WIRE 16 -1 (-7350 3600)(-7450 3600);
WIRE 16 -1 (-7450 3600)(-7450 3450);
WIRE 16 -1 (-7050 3600)(-7350 3600);
WIRE 16 -1 (-7350 3450)(-7350 3600);
WIRE 16 -1 (-7050 3450)(-7050 3600);
WIRE 16 -1 (-3550 3275)(-3550 3300);
WIRE 16 -1 (-3600 3300)(-3550 3300);
WIRE 16 -1 (-5900 3500)(-5900 3550);
WIRE 16 -1 (-5200 4400)(-5200 4350);
WIRE 16 -1 (-5200 4350)(-4400 4350);
WIRE 16 -1 (-5200 4350)(-5200 4300);
WIRE 16 -1 (-4400 4350)(-4400 4050);
WIRE 16 -1 (-4400 4050)(-4300 4050);
WIRE 16 -1 (-5200 4100)(-5200 4050);
WIRE 16 -1 (-1750 3900)(-1750 3850);
WIRE 16 -1 (-6600 3500)(-6600 3550);
WIRE 16 -1 (-6600 4400)(-6600 4450);
WIRE 16 -1 (-6250 4400)(-6600 4400);
WIRE 16 -1 (-6600 4300)(-6600 4400);
WIRE 16 -1 (-5900 4400)(-6250 4400);
WIRE 16 -1 (-6250 4300)(-6250 4400);
WIRE 16 -1 (-5900 4300)(-5900 4400);
WIRE 16 -1 (-6250 3500)(-6250 3550);
WIRE 16 -1 (-1775 2500)(-1775 2400);
WIRE 16 -1 (-1775 2200)(-1775 2100);
WIRE 16 -1 (-3200 2450)(-3200 2300);
WIRE 16 -1 (-2700 1975)(-2700 2000);
WIRE 16 -1 (-2700 2000)(-2600 2000);
WIRE 16 -1 (-2600 2000)(-2600 1950);
WIRE 16 -1 (-2600 1950)(-2600 1900);
WIRE 16 -1 (-2500 1950)(-2600 1950);
WIRE 16 -1 (-2500 1900)(-2600 1900);
WIRE 16 -1 (-3200 1350)(-3200 1400);
WIRE 3 682 (-6850 3400)(-5400 3400);
WIRE 3 682 (-6850 4600)(-6850 3400);
WIRE 3 682 (-5400 3400)(-5400 4600);
WIRE 3 682 (-5400 4600)(-6850 4600);
WIRE 3 2175 (-4450 500)(-25 500);
WIRE 3 2175 (-25 2775)(-25 500);
WIRE 3 2175 (-4450 2775)(-4450 500);
WIRE 3 2175 (-4450 2775)(-25 2775);
WIRE 3 2175 (-7900 2900)(-100 2900);
WIRE 3 2175 (-100 4700)(-100 2900);
WIRE 3 2175 (-7900 4700)(-7900 2900);
WIRE 3 2175 (-7900 4700)(-100 4700);
WIRE 16 -1 (-1900 1750)(-1125 1750);
FORCEPROP 2 LAST SIG_NAME SMB_HOST_STBY_LVC3_SDA_R3
J 0
(-1810 1760);
DISPLAY 0.702128 (-1810 1760);
PAINT ORANGE (-1810 1760);
FORCEPROP 2 LASTPROP $XRERR UNIQUE?
J 0
(-2050 1760);
DISPLAY 0.638298 (-2050 1760);
PAINT MONO (-2050 1760);
DISPLAY INVISIBLE (-2050 1760);
WIRE 16 -1 (-3600 3650)(-2650 3650);
FORCEPROP 2 LAST SIG_NAME RST_PLTRST_N
J 0
(-3460 3660);
DISPLAY 0.617021 (-3460 3660);
PAINT ORANGE (-3460 3660);
WIRE 16 -1 (-3600 3700)(-2650 3700);
FORCEPROP 2 LAST SIG_NAME PWRGD_SYS_PWROK
J 0
(-3460 3710);
DISPLAY 0.617021 (-3460 3710);
PAINT ORANGE (-3460 3710);
WIRE 16 -1 (-3600 3750)(-2650 3750);
FORCEPROP 2 LAST SIG_NAME FP_PWR_BTN_R_N
J 0
(-3460 3760);
DISPLAY 0.702128 (-3460 3760);
PAINT ORANGE (-3460 3760);
WIRE 16 -1 (-3600 3800)(-2650 3800);
FORCEPROP 2 LAST SIG_NAME FM_DEBUG_RST_BTN_N
J 0
(-3460 3810);
DISPLAY 0.680851 (-3460 3810);
PAINT ORANGE (-3460 3810);
WIRE 16 -1 (-2650 3900)(-3600 3900);
FORCEPROP 2 LAST SIG_NAME SMB_DEBUG_STBY_LVC3_SCL
J 0
(-3435 3910);
DISPLAY 0.680851 (-3435 3910);
PAINT ORANGE (-3435 3910);
WIRE 16 -1 (-2650 3950)(-3600 3950);
FORCEPROP 2 LAST SIG_NAME SMB_DEBUG_STBY_LVC3_SDA
J 0
(-3435 3960);
DISPLAY 0.680851 (-3435 3960);
PAINT ORANGE (-3435 3960);
WIRE 16 -1 (-2925 4050)(-3600 4050);
FORCEPROP 2 LAST SIG_NAME PCA9555_INT_N
J 0
(-3435 4060);
DISPLAY 0.680851 (-3435 4060);
PAINT ORANGE (-3435 4060);
FORCEPROP 2 LASTPROP $XR0 247 
J 0
(-2895 4050);
DISPLAY 0.638298 (-2895 4050);
PAINT MONO (-2895 4050);
WIRE 16 -1 (-3600 3600)(-2650 3600);
FORCEPROP 2 LAST SIG_NAME PWRGD_DSW_PWROK
J 0
(-3460 3610);
DISPLAY 0.617021 (-3460 3610);
PAINT ORANGE (-3460 3610);
WIRE 16 -1 (-1450 3650)(-1500 3650);
WIRE 16 -1 (-1500 3450)(-1450 3450);
WIRE 16 -1 (-1500 3550)(-1500 3450);
WIRE 16 -1 (-1500 3650)(-1500 3550);
WIRE 16 -1 (-1750 3650)(-1750 3550);
WIRE 16 -1 (-1750 3550)(-1500 3550);
WIRE 16 -1 (-3600 3550)(-1750 3550);
FORCEPROP 2 LAST SIG_NAME FM_CPU_CATERR_MSMI_LVT3_N
J 0
(-3460 3560);
DISPLAY 0.617021 (-3460 3560);
PAINT ORANGE (-3460 3560);
FORCEPROP 2 LASTPROP $XRERR UNIQUE?
J 0
(-3700 3560);
DISPLAY 0.638298 (-3700 3560);
PAINT MONO (-3700 3560);
DISPLAY INVISIBLE (-3700 3560);
WIRE 3 682 (-2250 3100)(-2200 3100);
WIRE 3 682 (-2250 3450)(-2250 3100);
WIRE 3 682 (-2300 3450)(-2250 3450);
WIRE 3 682 (-1150 4100)(-1150 3250);
WIRE 3 682 (-1850 4100)(-1150 4100);
WIRE 3 682 (-1150 3250)(-1850 3250);
WIRE 3 682 (-1850 3250)(-1850 4100);
WIRE 16 -1 (-2650 3450)(-3600 3450);
FORCEPROP 2 LAST SIG_NAME FM_UART_SWITCH_N
J 0
(-3460 3460);
DISPLAY 0.638298 (-3460 3460);
PAINT ORANGE (-3460 3460);
WIRE 16 -1 (-925 1750)(-325 1750);
FORCEPROP 2 LAST SIG_NAME SMB_HOST_STBY_LVC3_SDA
J 0
(-885 1760);
DISPLAY 0.680851 (-885 1760);
PAINT ORANGE (-885 1760);
WIRE 16 -1 (-3600 3500)(-2650 3500);
FORCEPROP 2 LAST SIG_NAME FM_SLPS3_N
J 0
(-3460 3510);
DISPLAY 0.617021 (-3460 3510);
PAINT ORANGE (-3460 3510);
WIRE 3 682 (-3225 1825)(-3225 2025);
WIRE 3 682 (-2275 1825)(-3225 1825);
WIRE 3 682 (-3225 2025)(-2275 2025);
WIRE 3 682 (-2275 2025)(-2275 1825);
WIRE 16 -1 (-3200 2100)(-3200 1850);
WIRE 16 -1 (-2500 1850)(-3200 1850);
FORCEPROP 2 LAST SIG_NAME PU_ID_EEPROM_A0
J 0
(-3135 1860);
DISPLAY 0.617021 (-3135 1860);
PAINT ORANGE (-3135 1860);
FORCEPROP 2 LASTPROP $XRERR UNIQUE?
J 0
(-3375 1860);
DISPLAY 0.638298 (-3375 1860);
PAINT MONO (-3375 1860);
DISPLAY INVISIBLE (-3375 1860);
WIRE 16 -1 (-3325 1750)(-2500 1750);
FORCEPROP 2 LAST SIG_NAME SMB_HOST_STBY_LVC3_SCL_R3
J 0
(-3260 1760);
DISPLAY 0.680851 (-3260 1760);
PAINT ORANGE (-3260 1760);
FORCEPROP 2 LASTPROP $XRERR UNIQUE?
J 0
(-3500 1760);
DISPLAY 0.638298 (-3500 1760);
PAINT MONO (-3500 1760);
DISPLAY INVISIBLE (-3500 1760);
WIRE 16 -1 (-3200 1700)(-3200 1600);
WIRE 16 -1 (-2500 1700)(-3200 1700);
FORCEPROP 2 LAST SIG_NAME PD_ID_EEPROM_WP
J 0
(-3160 1710);
DISPLAY 0.617021 (-3160 1710);
PAINT ORANGE (-3160 1710);
FORCEPROP 2 LASTPROP $XRERR UNIQUE?
J 0
(-3400 1710);
DISPLAY 0.638298 (-3400 1710);
PAINT MONO (-3400 1710);
DISPLAY INVISIBLE (-3400 1710);
WIRE 16 -1 (-4300 3800)(-5000 3800);
FORCEPROP 2 LAST SIG_NAME PCA9555_A2
J 0
(-4935 3810);
DISPLAY 0.680851 (-4935 3810);
PAINT ORANGE (-4935 3810);
FORCEPROP 2 LASTPROP $XR0 247 
J 0
(-5096 3800);
DISPLAY 0.638298 (-5096 3800);
PAINT MONO (-5096 3800);
WIRE 16 -1 (-4300 3850)(-5000 3850);
FORCEPROP 2 LAST SIG_NAME PCA9555_A1
J 0
(-4935 3860);
DISPLAY 0.680851 (-4935 3860);
PAINT ORANGE (-4935 3860);
FORCEPROP 2 LASTPROP $XR0 247 
J 0
(-5096 3850);
DISPLAY 0.638298 (-5096 3850);
PAINT MONO (-5096 3850);
WIRE 16 -1 (-5000 3650)(-4300 3650);
FORCEPROP 2 LAST SIG_NAME LED_POSTCODE_0_R
J 0
(-4950 3660);
DISPLAY 0.617021 (-4950 3660);
PAINT ORANGE (-4950 3660);
WIRE 3 2175 (-3850 3425)(-3650 3425);
WIRE 3 2175 (-3650 3725)(-3650 3425);
WIRE 3 2175 (-3850 3725)(-3850 3425);
WIRE 3 2175 (-3850 3725)(-3650 3725);
WIRE 16 -1 (-5900 3850)(-5600 3850);
FORCEPROP 2 LAST SIG_NAME PCA9555_A0
J 0
(-5860 3860);
DISPLAY 0.680851 (-5860 3860);
PAINT ORANGE (-5860 3860);
FORCEPROP 2 LASTPROP $XR0 247 
J 0
(-5510 3850);
DISPLAY 0.638298 (-5510 3850);
PAINT MONO (-5510 3850);
WIRE 16 -1 (-5900 4100)(-5900 3850);
WIRE 16 -1 (-5900 3750)(-5900 3850);
WIRE 16 -1 (-500 3450)(-1250 3450);
FORCEPROP 2 LAST SIG_NAME FM_CPU_MSMI_LVT3_N
J 0
(-1085 3460);
DISPLAY 0.638298 (-1085 3460);
PAINT ORANGE (-1085 3460);
WIRE 16 -1 (-1250 3650)(-500 3650);
FORCEPROP 2 LAST SIG_NAME FM_CPU_CATERR_LVT3_N
J 0
(-1085 3660);
DISPLAY 0.617021 (-1085 3660);
PAINT ORANGE (-1085 3660);
WIRE 16 -1 (-6250 3750)(-6250 3900);
WIRE 16 -1 (-6250 3900)(-5600 3900);
FORCEPROP 2 LAST SIG_NAME PCA9555_A1
J 0
(-5860 3910);
DISPLAY 0.680851 (-5860 3910);
PAINT ORANGE (-5860 3910);
FORCEPROP 2 LASTPROP $XR0 247 
J 0
(-5510 3900);
DISPLAY 0.638298 (-5510 3900);
PAINT MONO (-5510 3900);
WIRE 16 -1 (-6250 4100)(-6250 3900);
WIRE 16 -1 (-6600 3750)(-6600 3950);
WIRE 16 -1 (-6600 3950)(-5600 3950);
FORCEPROP 2 LAST SIG_NAME PCA9555_A2
J 0
(-5860 3960);
DISPLAY 0.680851 (-5860 3960);
PAINT ORANGE (-5860 3960);
FORCEPROP 2 LASTPROP $XR0 247 
J 0
(-5510 3950);
DISPLAY 0.638298 (-5510 3950);
PAINT MONO (-5510 3950);
WIRE 16 -1 (-6600 3950)(-6600 4100);
WIRE 16 -1 (-5000 3550)(-4300 3550);
FORCEPROP 2 LAST SIG_NAME LED_POSTCODE_2_R
J 0
(-4950 3560);
DISPLAY 0.617021 (-4950 3560);
PAINT ORANGE (-4950 3560);
WIRE 16 -1 (-5000 3600)(-4300 3600);
FORCEPROP 2 LAST SIG_NAME LED_POSTCODE_1_R
J 0
(-4950 3610);
DISPLAY 0.617021 (-4950 3610);
PAINT ORANGE (-4950 3610);
WIRE 16 -1 (-5000 3300)(-4300 3300);
FORCEPROP 2 LAST SIG_NAME LED_POSTCODE_7_R
J 0
(-4950 3310);
DISPLAY 0.617021 (-4950 3310);
PAINT ORANGE (-4950 3310);
WIRE 16 -1 (-5000 3450)(-4300 3450);
FORCEPROP 2 LAST SIG_NAME LED_POSTCODE_4_R
J 0
(-4950 3460);
DISPLAY 0.617021 (-4950 3460);
PAINT ORANGE (-4950 3460);
WIRE 16 -1 (-5000 3400)(-4300 3400);
FORCEPROP 2 LAST SIG_NAME LED_POSTCODE_5_R
J 0
(-4950 3410);
DISPLAY 0.617021 (-4950 3410);
PAINT ORANGE (-4950 3410);
WIRE 16 -1 (-5000 3500)(-4300 3500);
FORCEPROP 2 LAST SIG_NAME LED_POSTCODE_3_R
J 0
(-4950 3510);
DISPLAY 0.617021 (-4950 3510);
PAINT ORANGE (-4950 3510);
WIRE 16 -1 (-4300 3900)(-5000 3900);
FORCEPROP 2 LAST SIG_NAME PCA9555_A0
J 0
(-4935 3910);
DISPLAY 0.680851 (-4935 3910);
PAINT ORANGE (-4935 3910);
FORCEPROP 2 LASTPROP $XR0 247 
J 0
(-5096 3900);
DISPLAY 0.638298 (-5096 3900);
PAINT MONO (-5096 3900);
WIRE 3 2175 (-7900 2450)(-4500 2450);
WIRE 3 2175 (-4500 2450)(-4500 500);
WIRE 3 2175 (-7900 2450)(-7900 500);
WIRE 3 2175 (-7900 500)(-4500 500);
WIRE 16 -1 (-5000 3350)(-4300 3350);
FORCEPROP 2 LAST SIG_NAME LED_POSTCODE_6_R
J 0
(-4950 3360);
DISPLAY 0.617021 (-4950 3360);
PAINT ORANGE (-4950 3360);
WIRE 16 -1 (-7450 3250)(-7450 3000);
WIRE 16 -1 (-7450 3000)(-6250 3000);
FORCEPROP 2 LAST SIG_NAME PCA9555_INT_N
J 0
(-6985 3010);
DISPLAY 0.680851 (-6985 3010);
PAINT ORANGE (-6985 3010);
FORCEPROP 2 LASTPROP $XR0 247 
J 0
(-6220 3000);
DISPLAY 0.638298 (-6220 3000);
PAINT MONO (-6220 3000);
WIRE 16 -1 (-7350 3250)(-7350 3050);
WIRE 16 -1 (-7350 3050)(-6250 3050);
FORCEPROP 2 LAST SIG_NAME SMB_DEBUG_STBY_LVC3_SCL
J 0
(-6985 3060);
DISPLAY 0.680851 (-6985 3060);
PAINT ORANGE (-6985 3060);
FORCEPROP 2 LASTPROP $XR2 247 
J 0
(-5980 3050);
DISPLAY 0.638298 (-5980 3050);
PAINT MONO (-5980 3050);
FORCEPROP 2 LASTPROP $XR1 176 
J 0
(-6100 3050);
DISPLAY 0.638298 (-6100 3050);
PAINT MONO (-6100 3050);
FORCEPROP 2 LASTPROP $XR0 145 
J 0
(-6220 3050);
DISPLAY 0.638298 (-6220 3050);
PAINT MONO (-6220 3050);
WIRE 16 -1 (-7050 3250)(-7050 3100);
WIRE 16 -1 (-7050 3100)(-6250 3100);
FORCEPROP 2 LAST SIG_NAME SMB_DEBUG_STBY_LVC3_SDA
J 0
(-6985 3110);
DISPLAY 0.680851 (-6985 3110);
PAINT ORANGE (-6985 3110);
FORCEPROP 2 LASTPROP $XR2 247 
J 0
(-5980 3100);
DISPLAY 0.638298 (-5980 3100);
PAINT MONO (-5980 3100);
FORCEPROP 2 LASTPROP $XR1 176 
J 0
(-6100 3100);
DISPLAY 0.638298 (-6100 3100);
PAINT MONO (-6100 3100);
FORCEPROP 2 LASTPROP $XR0 145 
J 0
(-6220 3100);
DISPLAY 0.638298 (-6220 3100);
PAINT MONO (-6220 3100);
WIRE 16 -1 (-7525 900)(-6700 900);
FORCEPROP 0 LAST CDS_PHYS_NET_NAME SMB_PMBUS_BMC_STBY_LVC3_SDA_R1
J 0
(-7550 939);
PAINT MONO (-7550 939);
DISPLAY INVISIBLE (-7550 939);
FORCEPROP 2 LAST SIG_NAME SMB_PMBUS_BMC_STBY_LVC3_SDA_R1
J 0
(-7525 910);
DISPLAY 0.617021 (-7525 910);
PAINT ORANGE (-7525 910);
WIRE 16 -1 (-7525 950)(-6700 950);
FORCEPROP 0 LAST CDS_PHYS_NET_NAME SMB_PMBUS_BMC_STBY_LVC3_SCL_R1
J 0
(-7525 989);
PAINT MONO (-7525 989);
DISPLAY INVISIBLE (-7525 989);
FORCEPROP 2 LAST SIG_NAME SMB_PMBUS_BMC_STBY_LVC3_SCL_R1
J 0
(-7525 960);
DISPLAY 0.617021 (-7525 960);
PAINT ORANGE (-7525 960);
WIRE 16 -1 (-7550 1850)(-7550 1650);
WIRE 16 -1 (-7550 1650)(-5975 1650);
FORCEPROP 2 LAST SIG_NAME SMB_PMBUS_BMC_STBY_LVC3_SDA_R1
J 0
(-6750 1660);
DISPLAY 0.617021 (-6750 1660);
PAINT ORANGE (-6750 1660);
FORCEPROP 2 LASTPROP $XR1 247 
J 0
(-5735 1650);
DISPLAY 0.638298 (-5735 1650);
PAINT MONO (-5735 1650);
FORCEPROP 2 LASTPROP $XR0 119 
J 0
(-5855 1650);
DISPLAY 0.638298 (-5855 1650);
PAINT MONO (-5855 1650);
WIRE 16 -1 (-7200 1850)(-7200 1700);
WIRE 16 -1 (-7200 1700)(-5975 1700);
FORCEPROP 2 LAST SIG_NAME SMB_PMBUS_BMC_STBY_LVC3_SCL_R1
J 0
(-6750 1710);
DISPLAY 0.617021 (-6750 1710);
PAINT ORANGE (-6750 1710);
FORCEPROP 2 LASTPROP $XR1 247 
J 0
(-5735 1700);
DISPLAY 0.638298 (-5735 1700);
PAINT MONO (-5735 1700);
FORCEPROP 2 LASTPROP $XR0 119 
J 0
(-5855 1700);
DISPLAY 0.638298 (-5855 1700);
PAINT MONO (-5855 1700);
WIRE 16 -1 (-6850 1850)(-6850 1750);
WIRE 16 -1 (-6850 1750)(-5975 1750);
FORCEPROP 2 LAST SIG_NAME HSC_SMBUS_SWITCH_EN
J 0
(-6760 1760);
DISPLAY 0.702128 (-6760 1760);
PAINT ORANGE (-6760 1760);
FORCEPROP 2 LASTPROP $XR1 247 
J 0
(-5825 1750);
DISPLAY 0.638298 (-5825 1750);
PAINT MONO (-5825 1750);
FORCEPROP 2 LASTPROP $XR0 146 
J 0
(-5945 1750);
DISPLAY 0.638298 (-5945 1750);
PAINT MONO (-5945 1750);
WIRE 16 -1 (-6050 950)(-5100 950);
FORCEPROP 0 LAST CDS_PHYS_NET_NAME SMB_BMC_PMBUS_STBY_LVC3_SCL
J 0
(-5175 989);
PAINT MONO (-5175 989);
DISPLAY INVISIBLE (-5175 989);
FORCEPROP 2 LAST SIG_NAME SMB_BMC_PMBUS_STBY_LVC3_SCL
J 0
(-5935 960);
DISPLAY 0.638298 (-5935 960);
PAINT ORANGE (-5935 960);
WIRE 16 -1 (-5100 900)(-6050 900);
FORCEPROP 0 LAST CDS_PHYS_NET_NAME SMB_BMC_PMBUS_STBY_LVC3_SDA
J 0
(-5150 939);
PAINT MONO (-5150 939);
DISPLAY INVISIBLE (-5150 939);
FORCEPROP 2 LAST SIG_NAME SMB_BMC_PMBUS_STBY_LVC3_SDA
J 0
(-5935 910);
DISPLAY 0.638298 (-5935 910);
PAINT ORANGE (-5935 910);
WIRE 16 -1 (-5100 850)(-6050 850);
FORCEPROP 2 LAST SIG_NAME HSC_SMBUS_SWITCH_EN
J 0
(-5935 860);
DISPLAY 0.702128 (-5935 860);
PAINT ORANGE (-5935 860);
WIRE 16 -1 (-4150 1750)(-3525 1750);
FORCEPROP 2 LAST SIG_NAME SMB_HOST_STBY_LVC3_SCL
J 0
(-4160 1760);
DISPLAY 0.680851 (-4160 1760);
PAINT ORANGE (-4160 1760);
DOT 1 (-1750 3550);
DOT 1 (-5200 4350);
DOT 1 (-6600 4400);
DOT 1 (-6250 3900);
DOT 1 (-1500 3550);
DOT 1 (-6600 3950);
DOT 1 (-6250 4400);
DOT 1 (-5900 3850);
DOT 1 (-7450 3600);
DOT 1 (-7350 3600);
DOT 1 (-5950 1400);
DOT 1 (-7550 2150);
DOT 1 (-6900 1400);
DOT 1 (-7200 2150);
DOT 1 (-2600 1950);
FORCENOTE
CONNECT TO SWITCH DIRECTLY
(-3350 3175) 0;
DISPLAY LEFT (-3350 3175);
DISPLAY 1.021277 (-3350 3175);
PAINT PURPLE (-3350 3175);
FORCENOTE
SMBUS ADDRESS 0XA2
(-1825 1125) 0;
DISPLAY LEFT (-1825 1125);
DISPLAY 1.021277 (-1825 1125);
PAINT PURPLE (-1825 1125);
FORCENOTE
TP FAB1 ADD I2C TO GPIO BRIDGE FOR USB3.0 BEBUG PORT 1117
(-7875 4750) 0;
DISPLAY LEFT (-7875 4750);
DISPLAY 1.021277 (-7875 4750);
PAINT RED (-7875 4750);
FORCENOTE
TP FAB1 ADD ONE SMALL EEPROM UNDER HOST SMBUS FOR BIOS SOFT BROAD_ID
(-4400 2700) 0;
DISPLAY LEFT (-4400 2700);
DISPLAY 1.021277 (-4400 2700);
PAINT RED (-4400 2700);
FORCENOTE
TP FAB3 RECONNECTION 0926
(-2175 3075) 0;
DISPLAY LEFT (-2175 3075);
DISPLAY 0.638298 (-2175 3075);
PAINT RED (-2175 3075);
FORCENOTE
TP FAB3 CHANGE R6W35 RES 0825
(-1875 3125) 0;
DISPLAY LEFT (-1875 3125);
DISPLAY 1.021277 (-1875 3125);
PAINT RED (-1875 3125);
FORCENOTE
TP FAB3 ADD RES AND DIODES 0803
(-1875 3175) 0;
DISPLAY LEFT (-1875 3175);
DISPLAY 1.021277 (-1875 3175);
PAINT RED (-1875 3175);
FORCENOTE
TP FAB3 CHANGE P18 ABD P20 CONNECTION 0803
(-3450 3300) 0;
DISPLAY LEFT (-3450 3300);
DISPLAY 0.638298 (-3450 3300);
PAINT RED (-3450 3300);
FORCENOTE
TP FAB1 CONNECT P20 0314
(-3450 3350) 0;
DISPLAY LEFT (-3450 3350);
DISPLAY 0.638298 (-3450 3350);
PAINT RED (-3450 3350);
FORCENOTE
TP FAB1 CONNECT P12~P16 1221
(-3450 3400) 0;
DISPLAY LEFT (-3450 3400);
DISPLAY 0.638298 (-3450 3400);
PAINT RED (-3450 3400);
FORCENOTE
TP FAB3 RECONNECTION 0905
(-3450 3250) 0;
DISPLAY LEFT (-3450 3250);
DISPLAY 0.638298 (-3450 3250);
PAINT RED (-3450 3250);
FORCENOTE
TP FAB1 CHANGE PCA9555 TO TCA9555
(-4250 3050) 0;
DISPLAY LEFT (-4250 3050);
DISPLAY 1.021277 (-4250 3050);
PAINT RED (-4250 3050);
FORCENOTE
TP FAB1 CHANGE U6W2 FROM PCA9515 TO PCA9517 1210
(-7925 2650) 0;
DISPLAY LEFT (-7925 2650);
DISPLAY 1.021277 (-7925 2650);
PAINT RED (-7925 2650);
FORCENOTE
TP FAB1 ADD   R6W24 AND R6W25 PU RESISTOR 1210
(-7925 2575) 0;
DISPLAY LEFT (-7925 2575);
DISPLAY 1.021277 (-7925 2575);
PAINT RED (-7925 2575);
FORCENOTE
TP FAB1 U6W2 FROM PCA9517 CHANGE TO TCA9517 0106
(-7925 2500) 0;
DISPLAY LEFT (-7925 2500);
DISPLAY 1.021277 (-7925 2500);
PAINT RED (-7925 2500);
FORCENOTE
TP FAB3 POP R6W4, R6W5 AND R6W6; NOPOP R6W7, R6W8 AND R6W9 0819
(-6850 4625) 0;
DISPLAY LEFT (-6850 4625);
DISPLAY 0.638298 (-6850 4625);
PAINT RED (-6850 4625);
FORCENOTE
ADDRESS 0X4E
(-4250 4600) 0;
DISPLAY LEFT (-4250 4600);
DISPLAY 1.021277 (-4250 4600);
PAINT PURPLE (-4250 4600);
FORCENOTE
TP FAB3 RECONNECTION 0902
(-3150 2025) 0;
DISPLAY LEFT (-3150 2025);
DISPLAY 0.638298 (-3150 2025);
PAINT RED (-3150 2025);
FORCENOTE
TP FAB1 ADD A SMBUS MASTER SWITCH FOR HSC ACCESS FROM ME OR BMC, CONTROLLED BY BMC 1127
(-7925 2725) 0;
DISPLAY LEFT (-7925 2725);
DISPLAY 1.021277 (-7925 2725);
PAINT RED (-7925 2725);
QUIT
